# Altium SchDoc records: 02-USER_IO_STATUS.SchDoc
|HEADER=Protel for Windows - Schematic Capture Binary File Version 5.0|Weight=1170|MinorVersion=6
|RECORD=31|FontIdCount=17|Size1=10|FontName1=Times New Roman|Size2=10|Rotation2=90|FontName2=Times New Roman|Size3=8|FontName3=Arial|Size4=10|FontName4=Arial|Size5=10|Underline5=T|FontName5=Times New Roman|Size6=24|FontName6=Times New Roman|Size7=12|FontName7=Arial|Size8=14|FontName8=Times New Roman|Size9=14|FontName9=Arial|Size10=9|FontName10=Arial|Size11=9|FontName11=Arial Narrow|Size12=22|FontName12=Arial Narrow|Size13=14|FontName13=Arial Narrow|Size14=6|Rotation14=90|FontName14=Arial|Size15=6|FontName15=Arial|Size16=24|FontName16=Arial|Size17=9|Rotation17=90|FontName17=Arial|UseMBCS=T|IsBOC=T|HotSpotGridOn=T|HotSpotGridSize=4|SheetStyle=6|SystemFont=4|TitleBlockOn=T|SheetNumberSpaceSize=12|AreaColor=16317695|SnapGridOn=T|SnapGridSize=1|VisibleGridOn=T|VisibleGridSize=10|CustomX=1700|CustomY=1100|CustomXZones=8|CustomYZones=6|CustomMarginWidth=20|Display_Unit=0|ReferenceZoneStyle=1
|RECORD=39|IsNotAccesible=T|OwnerPartId=-1|FileName=C:\Users\<user>\Documents\Altium\AD21\Templates\ANSI B Landscape.SchDot
|RECORD=4|OwnerIndex=1|OwnerPartId=-1|Location.X=1345|Location.Y=1068|FontID=11|Text=REVISION
|RECORD=4|OwnerIndex=1|IndexInSheet=1|OwnerPartId=-1|Location.X=1460|Location.Y=1068|FontID=11|Text=DESCRIPTION
|RECORD=4|OwnerIndex=1|IndexInSheet=2|OwnerPartId=-1|Location.X=1592|Location.Y=1068|FontID=11|Text=DATE
|RECORD=4|OwnerIndex=1|IndexInSheet=3|OwnerPartId=-1|Location.X=1633|Location.Y=1068|FontID=11|Text=APPROVED
|RECORD=6|OwnerIndex=1|IndexInSheet=4|OwnerPartId=-1|LocationCount=3|X1=1340|Y1=1080|X2=1340|Y2=1065|X3=1680|Y3=1065
|RECORD=6|OwnerIndex=1|IndexInSheet=5|OwnerPartId=-1|LocationCount=2|X1=1380|Y1=1080|X2=1380|Y2=1065
|RECORD=6|OwnerIndex=1|IndexInSheet=6|OwnerPartId=-1|LocationCount=2|X1=1620|Y1=1080|X2=1620|Y2=1065
|RECORD=6|OwnerIndex=1|IndexInSheet=7|OwnerPartId=-1|LocationCount=2|X1=1580|Y1=1080|X2=1580|Y2=1065
|RECORD=6|OwnerIndex=1|IndexInSheet=8|OwnerPartId=-1|LocationCount=3|X1=1340|Y1=1070|X2=1340|Y2=1050|X3=1680|Y3=1050
|RECORD=6|OwnerIndex=1|IndexInSheet=9|OwnerPartId=-1|LocationCount=2|X1=1380|Y1=1065|X2=1380|Y2=1050
|RECORD=6|OwnerIndex=1|IndexInSheet=10|OwnerPartId=-1|LocationCount=2|X1=1580|Y1=1065|X2=1580|Y2=1050
|RECORD=6|OwnerIndex=1|IndexInSheet=11|OwnerPartId=-1|LocationCount=2|X1=1620|Y1=1065|X2=1620|Y2=1050
|RECORD=6|OwnerIndex=1|IndexInSheet=12|OwnerPartId=-1|LineWidth=1|LocationCount=2|X1=1695|Y1=184|X2=1700|Y2=184
|RECORD=4|OwnerIndex=1|IndexInSheet=13|OwnerPartId=-1|Location.X=1689|Location.Y=189|Orientation=3|FontID=14|Text=REV.
|RECORD=4|OwnerIndex=1|IndexInSheet=14|OwnerPartId=-1|Location.X=1689|Location.Y=174|Orientation=3|FontID=14|Text=SHT.
|RECORD=4|OwnerIndex=1|IndexInSheet=15|OwnerPartId=-1|Location.X=1695|Location.Y=259|Orientation=3|Justification=6|FontID=14|Text=DWG. NO.|IsMirrored=T
|RECORD=4|OwnerIndex=1|IndexInSheet=16|OwnerPartId=-1|Location.X=1680|Location.Y=258|Orientation=3|FontID=17|Text==DOC_NO_SCH_DWG
|RECORD=4|OwnerIndex=1|IndexInSheet=17|OwnerPartId=-1|Location.X=1680|Location.Y=182|Orientation=3|Justification=1|FontID=17|Text==ItemRevision
|RECORD=4|OwnerIndex=1|IndexInSheet=18|OwnerPartId=-1|Location.X=1680|Location.Y=169|Orientation=3|Justification=1|FontID=17|Text==SheetNumber
|RECORD=6|OwnerIndex=1|IndexInSheet=19|OwnerPartId=-1|LineWidth=1|LocationCount=3|X1=1695|Y1=160|X2=1695|Y2=260|X3=1680|Y3=260
|RECORD=6|OwnerIndex=1|IndexInSheet=20|OwnerPartId=-1|LocationCount=2|X1=1695|Y1=175|X2=1680|Y2=175
|RECORD=6|OwnerIndex=1|IndexInSheet=21|OwnerPartId=-1|LocationCount=2|X1=1695|Y1=190|X2=1680|Y2=190
|RECORD=6|OwnerIndex=1|IndexInSheet=22|OwnerPartId=-1|LineWidth=1|LocationCount=2|X1=1695|Y1=160|X2=1680|Y2=160
|RECORD=4|OwnerIndex=1|IndexInSheet=23|OwnerPartId=-1|Location.X=1312|Location.Y=1080|FontID=15|Text=REV.
|RECORD=4|OwnerIndex=1|IndexInSheet=24|OwnerPartId=-1|Location.X=1327|Location.Y=1080|FontID=15|Text=SHT.
|RECORD=4|OwnerIndex=1|IndexInSheet=25|OwnerPartId=-1|Location.X=1283|Location.Y=1086|Justification=6|FontID=15|Text=DWG. NO.|IsMirrored=T
|RECORD=4|OwnerIndex=1|IndexInSheet=26|OwnerPartId=-1|Location.X=1247|Location.Y=1085|FontID=10|Text==DOC_NO_SCH_DWG
|RECORD=4|OwnerIndex=1|IndexInSheet=27|OwnerPartId=-1|Location.X=1317|Location.Y=1085|Justification=1|FontID=10|Text==ItemRevision
|RECORD=4|OwnerIndex=1|IndexInSheet=28|OwnerPartId=-1|Location.X=1332|Location.Y=1085|Justification=1|FontID=10|Text==SheetNumber
|RECORD=6|OwnerIndex=1|IndexInSheet=29|OwnerPartId=-1|LineWidth=1|LocationCount=3|X1=1340|Y1=1095|X2=1240|Y2=1095|X3=1240|Y3=1080
|RECORD=6|OwnerIndex=1|IndexInSheet=30|OwnerPartId=-1|LocationCount=2|X1=1325|Y1=1095|X2=1325|Y2=1080
|RECORD=6|OwnerIndex=1|IndexInSheet=31|OwnerPartId=-1|LocationCount=2|X1=1310|Y1=1095|X2=1310|Y2=1080
|RECORD=6|OwnerIndex=1|IndexInSheet=32|OwnerPartId=-1|LineWidth=1|LocationCount=2|X1=1340|Y1=1095|X2=1340|Y2=1080
|RECORD=7|OwnerIndex=1|IndexInSheet=33|OwnerPartId=-1|IsSolid=T|LocationCount=3|X1=850|Y1=1080|X2=855|Y2=1090|X3=845|Y3=1090
|RECORD=7|OwnerIndex=1|IndexInSheet=34|OwnerPartId=-1|IsSolid=T|LocationCount=3|X1=850|Y1=20|X2=845|Y2=10|X3=855|Y3=10
|RECORD=7|OwnerIndex=1|IndexInSheet=35|OwnerPartId=-1|IsSolid=T|LocationCount=3|X1=1680|Y1=550|X2=1690|Y2=545|X3=1690|Y3=555
|RECORD=28|OwnerIndex=1|IndexInSheet=36|OwnerPartId=-1|UnionIndex=1|Location.X=25|Location.Y=1033|Corner.X=298|Corner.Y=1075|AreaColor=16777215|FontID=4|Alignment=1|WordWrap=T|Text=THIS DOCUMENT AND THE DATA DISCLOSED HEREIN OR HEREWITH IS THE PROPERTY OF ALTIUM LIMITED AND MAY BE FREELY DISTRIBUTED IN WHOLE. NO RIGHTS ARE RESERVED OR EXPRESS OR IMPLIED WARANTEE GIVEN.|TextMargin_Frac=5
|RECORD=6|OwnerIndex=1|IndexInSheet=37|OwnerPartId=-1|UnionIndex=1|LineWidth=1|LocationCount=5|X1=300|Y1=1080|X2=20|Y2=1080|X3=20|Y3=1032|X4=300|Y4=1032|X5=300|Y5=1080
|RECORD=13|OwnerIndex=1|IndexInSheet=38|OwnerPartId=-1|Location.Y=1100|Corner.X=1699|Corner.X_Frac=83312|Corner.Y=1100|LineWidth=1
|RECORD=13|OwnerIndex=1|IndexInSheet=39|OwnerPartId=-1|Location.X=1699|Location.X_Frac=83312|Location.Y=1100|Corner.X=1699|Corner.X_Frac=83312|Corner.Y_Frac=16696|LineWidth=1
|RECORD=13|OwnerIndex=1|IndexInSheet=40|OwnerPartId=-1|Location.X=1699|Location.X_Frac=83312|Location.Y_Frac=16696|Corner.Y_Frac=16696|LineWidth=1
|RECORD=13|OwnerIndex=1|IndexInSheet=41|OwnerPartId=-1|Location.Y_Frac=16696|Corner.Y=1100|LineWidth=1
|RECORD=13|OwnerIndex=1|IndexInSheet=42|OwnerPartId=-1|Location.X=20|Location.X_Frac=12|Location.Y=1079|Location.Y_Frac=99791|Corner.X=1679|Corner.X_Frac=83296|Corner.Y=1079|Corner.Y_Frac=99791|LineWidth=1
|RECORD=13|OwnerIndex=1|IndexInSheet=43|OwnerPartId=-1|Location.X=1679|Location.X_Frac=83296|Location.Y=1079|Location.Y_Frac=99791|Corner.X=1679|Corner.X_Frac=83296|Corner.Y=20|Corner.Y_Frac=16904|LineWidth=1
|RECORD=13|OwnerIndex=1|IndexInSheet=44|OwnerPartId=-1|Location.X=1679|Location.X_Frac=83296|Location.Y=20|Location.Y_Frac=16904|Corner.X=20|Corner.X_Frac=12|Corner.Y=20|Corner.Y_Frac=16904|LineWidth=1
|RECORD=13|OwnerIndex=1|IndexInSheet=45|OwnerPartId=-1|Location.X=20|Location.X_Frac=12|Location.Y=20|Location.Y_Frac=16904|Corner.X=20|Corner.X_Frac=12|Corner.Y=1079|Corner.Y_Frac=99791|LineWidth=1
|RECORD=13|OwnerIndex=1|IndexInSheet=46|OwnerPartId=-1|Location.X=1487|Location.X_Frac=50000|Location.Y=20|Corner.X=1487|Corner.X_Frac=50000|LineWidth=1
|RECORD=13|OwnerIndex=1|IndexInSheet=47|OwnerPartId=-1|Location.X=1487|Location.X_Frac=50000|Location.Y=1080|Corner.X=1487|Corner.X_Frac=50000|Corner.Y=1100|LineWidth=1
|RECORD=13|OwnerIndex=1|IndexInSheet=48|OwnerPartId=-1|Location.X=1275|Location.Y=20|Corner.X=1275|LineWidth=1
|RECORD=13|OwnerIndex=1|IndexInSheet=49|OwnerPartId=-1|Location.X=1275|Location.Y=1095|Corner.X=1275|Corner.Y=1100|LineWidth=1
|RECORD=13|OwnerIndex=1|IndexInSheet=50|OwnerPartId=-1|Location.X=1062|Location.X_Frac=50000|Location.Y=20|Corner.X=1062|Corner.X_Frac=50000|LineWidth=1
|RECORD=13|OwnerIndex=1|IndexInSheet=51|OwnerPartId=-1|Location.X=1062|Location.X_Frac=50000|Location.Y=1080|Corner.X=1062|Corner.X_Frac=50000|Corner.Y=1100|LineWidth=1
|RECORD=13|OwnerIndex=1|IndexInSheet=52|OwnerPartId=-1|Location.X=850|Location.Y=20|Corner.X=850|LineWidth=1
|RECORD=13|OwnerIndex=1|IndexInSheet=53|OwnerPartId=-1|Location.X=850|Location.Y=1080|Corner.X=850|Corner.Y=1100|LineWidth=1
|RECORD=13|OwnerIndex=1|IndexInSheet=54|OwnerPartId=-1|Location.X=637|Location.X_Frac=50000|Location.Y=20|Corner.X=637|Corner.X_Frac=50000|LineWidth=1
|RECORD=13|OwnerIndex=1|IndexInSheet=55|OwnerPartId=-1|Location.X=637|Location.X_Frac=50000|Location.Y=1080|Corner.X=637|Corner.X_Frac=50000|Corner.Y=1100|LineWidth=1
|RECORD=13|OwnerIndex=1|IndexInSheet=56|OwnerPartId=-1|Location.X=425|Location.Y=20|Corner.X=425|LineWidth=1
|RECORD=13|OwnerIndex=1|IndexInSheet=57|OwnerPartId=-1|Location.X=425|Location.Y=1080|Corner.X=425|Corner.Y=1100|LineWidth=1
|RECORD=13|OwnerIndex=1|IndexInSheet=58|OwnerPartId=-1|Location.X=212|Location.X_Frac=50000|Location.Y=20|Corner.X=212|Corner.X_Frac=50000|LineWidth=1
|RECORD=13|OwnerIndex=1|IndexInSheet=59|OwnerPartId=-1|Location.X=212|Location.X_Frac=50000|Location.Y=1080|Corner.X=212|Corner.X_Frac=50000|Corner.Y=1100|LineWidth=1
|RECORD=13|OwnerIndex=1|IndexInSheet=60|OwnerPartId=-1|Location.X=20|Location.Y=916|Location.Y_Frac=66664|Corner.Y=916|Corner.Y_Frac=66664|LineWidth=1
|RECORD=13|OwnerIndex=1|IndexInSheet=61|OwnerPartId=-1|Location.X=1680|Location.Y=916|Location.Y_Frac=66664|Corner.X=1700|Corner.Y=916|Corner.Y_Frac=66664|LineWidth=1
|RECORD=13|OwnerIndex=1|IndexInSheet=62|OwnerPartId=-1|Location.X=20|Location.Y=733|Location.Y_Frac=33328|Corner.Y=733|Corner.Y_Frac=33328|LineWidth=1
|RECORD=13|OwnerIndex=1|IndexInSheet=63|OwnerPartId=-1|Location.X=1680|Location.Y=733|Location.Y_Frac=33328|Corner.X=1700|Corner.Y=733|Corner.Y_Frac=33328|LineWidth=1
|RECORD=13|OwnerIndex=1|IndexInSheet=64|OwnerPartId=-1|Location.X=20|Location.Y=550|Corner.Y=550|LineWidth=1
|RECORD=13|OwnerIndex=1|IndexInSheet=65|OwnerPartId=-1|Location.X=1680|Location.Y=550|Corner.X=1700|Corner.Y=550|LineWidth=1
|RECORD=13|OwnerIndex=1|IndexInSheet=66|OwnerPartId=-1|Location.X=20|Location.Y=366|Location.Y_Frac=66664|Corner.Y=366|Corner.Y_Frac=66664|LineWidth=1
|RECORD=13|OwnerIndex=1|IndexInSheet=67|OwnerPartId=-1|Location.X=1680|Location.Y=366|Location.Y_Frac=66664|Corner.X=1700|Corner.Y=366|Corner.Y_Frac=66664|LineWidth=1
|RECORD=13|OwnerIndex=1|IndexInSheet=68|OwnerPartId=-1|Location.X=20|Location.Y=183|Location.Y_Frac=33330|Corner.Y=183|Corner.Y_Frac=33330|LineWidth=1
|RECORD=7|OwnerIndex=1|IndexInSheet=69|OwnerPartId=-1|IsSolid=T|LocationCount=3|X1=20|Y1=550|X2=10|Y2=545|X3=10|Y3=555
|RECORD=4|OwnerIndex=1|IndexInSheet=70|OwnerPartId=-1|Location.X=1348|Location.Y=71|FontID=16|Text==title
|RECORD=4|OwnerIndex=1|IndexInSheet=71|OwnerPartId=-1|Location.X=1450|Location.Y=40|FontID=13|Text==DOC_NO_SCH_DWG
|RECORD=6|OwnerIndex=1|IndexInSheet=72|OwnerPartId=-1|LocationCount=2|X1=1405|Y1=65|X2=1405|Y2=35
|RECORD=6|OwnerIndex=1|IndexInSheet=73|OwnerPartId=-1|LocationCount=2|X1=1680|Y1=35|X2=1320|Y2=35
|RECORD=6|OwnerIndex=1|IndexInSheet=74|OwnerPartId=-1|LocationCount=2|X1=1650|Y1=65|X2=1650|Y2=35
|RECORD=4|OwnerIndex=1|IndexInSheet=75|OwnerPartId=-1|Location.X=1330|Location.Y=35|FontID=12|Text=B
|RECORD=4|OwnerIndex=1|IndexInSheet=76|OwnerPartId=-1|Location.X=1428|Location.Y=20|FontID=7|Text==DocumentName
|RECORD=4|OwnerIndex=1|IndexInSheet=77|OwnerPartId=-1|Location.X=1615|Location.Y=20|FontID=7|Text==SheetNumber
|RECORD=4|OwnerIndex=1|IndexInSheet=78|OwnerPartId=-1|Location.X=1655|Location.Y=20|FontID=7|Text==SheetTotal
|RECORD=4|OwnerIndex=1|IndexInSheet=79|OwnerPartId=-1|Location.X=1323|Location.Y=100|Justification=3|FontID=3|Text=TITLE
|RECORD=4|OwnerIndex=1|IndexInSheet=80|OwnerPartId=-1|Location.X=1328|Location.Y=60|Justification=3|FontID=3|Text=SIZE
|RECORD=4|OwnerIndex=1|IndexInSheet=81|OwnerPartId=-1|Location.X=1407|Location.Y=60|Justification=3|FontID=3|Text=DWG NO.
|RECORD=4|OwnerIndex=1|IndexInSheet=82|OwnerPartId=-1|Location.X=1387|Location.Y=30|Justification=3|FontID=3|Text=FILE NAME
|RECORD=4|OwnerIndex=1|IndexInSheet=83|OwnerPartId=-1|Location.X=1582|Location.Y=30|Justification=3|FontID=3|Text=SHEET
|RECORD=4|OwnerIndex=1|IndexInSheet=84|OwnerPartId=-1|Location.X=1640|Location.Y=30|Justification=3|FontID=3|Text=OF
|RECORD=4|OwnerIndex=1|IndexInSheet=85|OwnerPartId=-1|Location.X=1657|Location.Y=60|Justification=3|FontID=3|Text=REV
|RECORD=6|OwnerIndex=1|IndexInSheet=86|OwnerPartId=-1|LocationCount=2|X1=1385|Y1=35|X2=1385|Y2=20
|RECORD=4|OwnerIndex=1|IndexInSheet=87|OwnerPartId=-1|Location.X=1322|Location.Y=30|Justification=3|FontID=3|Text=SCALE:
|RECORD=4|OwnerIndex=1|IndexInSheet=88|OwnerPartId=-1|Location.X=1349|Location.Y=20|FontID=7|Text==SCH_SCALE
|RECORD=6|OwnerIndex=1|IndexInSheet=89|OwnerPartId=-1|LocationCount=2|X1=1580|Y1=35|X2=1580|Y2=20
|RECORD=4|OwnerIndex=1|IndexInSheet=90|OwnerPartId=-1|Location.X=1355|Location.Y=40|FontID=9|Text==CAGE_CODE
|RECORD=4|OwnerIndex=1|IndexInSheet=91|OwnerPartId=-1|Location.X=1352|Location.Y=56|FontID=3|Text=CAGE CODE
|RECORD=6|OwnerIndex=1|IndexInSheet=92|OwnerPartId=-1|LocationCount=2|X1=1350|Y1=65|X2=1350|Y2=35
|RECORD=6|OwnerIndex=1|IndexInSheet=93|OwnerPartId=-1|LineWidth=1|LocationCount=2|X1=1680|Y1=120|X2=1320|Y2=120
|RECORD=6|OwnerIndex=1|IndexInSheet=94|OwnerPartId=-1|LineWidth=1|LocationCount=2|X1=1680|Y1=160|X2=1320|Y2=160
|RECORD=4|OwnerIndex=1|IndexInSheet=95|OwnerPartId=-1|Location.X=1323|Location.Y=150|FontID=3|Text=PROJECT
|RECORD=6|OwnerIndex=1|IndexInSheet=96|OwnerPartId=-1|LocationCount=2|X1=1390|Y1=160|X2=1390|Y2=120
|RECORD=4|OwnerIndex=1|IndexInSheet=97|OwnerPartId=-1|Location.X=1325|Location.Y=130|FontID=9|Text==Project
|RECORD=4|OwnerIndex=1|IndexInSheet=98|OwnerPartId=-1|Location.X=1613|Location.Y=129|Justification=2|FontID=10|Text==Address3|IsMirrored=T
|RECORD=4|OwnerIndex=1|IndexInSheet=99|OwnerPartId=-1|Location.X=1614|Location.Y=120|Justification=2|FontID=10|Text==Address4|IsMirrored=T
|RECORD=4|OwnerIndex=1|IndexInSheet=100|OwnerPartId=-1|Location.X=1614|Location.Y=150|Justification=2|FontID=10|Text==Address1|IsMirrored=T
|RECORD=4|OwnerIndex=1|IndexInSheet=101|OwnerPartId=-1|Location.X=1614|Location.Y=144|Justification=5|FontID=10|Text==Address2|IsMirrored=T
|RECORD=6|OwnerIndex=1|IndexInSheet=102|OwnerPartId=1|LineWidth=1|LocationCount=2|X1=1320|Y1=65|X2=1320|Y2=35
|RECORD=6|OwnerIndex=1|IndexInSheet=103|OwnerPartId=1|LineWidth=1|LocationCount=2|X1=1320|Y1=35|X2=1320|Y2=20
|RECORD=6|OwnerIndex=1|IndexInSheet=104|OwnerPartId=1|LineWidth=1|LocationCount=2|X1=1320|Y1=65|X2=1320|Y2=120
|RECORD=6|OwnerIndex=1|IndexInSheet=105|OwnerPartId=1|LineWidth=1|LocationCount=2|X1=1320|Y1=120|X2=1320|Y2=160
|RECORD=6|OwnerIndex=1|IndexInSheet=106|OwnerPartId=1|LineWidth=1|LocationCount=3|X1=1320|Y1=160|X2=1180|Y2=160|X3=1180|Y3=20
|RECORD=4|OwnerIndex=1|IndexInSheet=107|OwnerPartId=1|Location.X=1212|Location.Y=145|FontID=3|Text=APPROVALS
|RECORD=4|OwnerIndex=1|IndexInSheet=108|OwnerPartId=1|Location.X=1290|Location.Y=145|FontID=3|Text=DATE
|RECORD=4|OwnerIndex=1|IndexInSheet=109|OwnerPartId=1|Location.X=1182|Location.Y=131|FontID=3|Text=ENG:
|RECORD=4|OwnerIndex=1|IndexInSheet=110|OwnerPartId=1|Location.X=1182|Location.Y=116|FontID=3|Text=DSN:
|RECORD=6|OwnerIndex=1|IndexInSheet=111|OwnerPartId=1|LocationCount=2|X1=1180|Y1=125|X2=1320|Y2=125
|RECORD=6|OwnerIndex=1|IndexInSheet=112|OwnerPartId=1|LocationCount=2|X1=1180|Y1=140|X2=1320|Y2=140
|RECORD=6|OwnerIndex=1|IndexInSheet=113|OwnerPartId=1|LocationCount=2|X1=1280|Y1=160|X2=1280|Y2=95
|RECORD=4|OwnerIndex=1|IndexInSheet=114|OwnerPartId=1|Location.X=1210|Location.Y=125|FontID=3|Text==Engineer
|RECORD=4|OwnerIndex=1|IndexInSheet=115|OwnerPartId=1|Location.X=1210|Location.Y=110|FontID=3|Text==DrawnBy
|RECORD=4|OwnerIndex=1|IndexInSheet=116|OwnerPartId=1|Location.X=1285|Location.Y=125|FontID=3|Text==ENG_APP_DATE
|RECORD=4|OwnerIndex=1|IndexInSheet=117|OwnerPartId=1|Location.X=1285|Location.Y=110|FontID=3|Text==DSN_APP_DATE
|RECORD=6|OwnerIndex=1|IndexInSheet=118|OwnerPartId=1|LineWidth=1|LocationCount=2|X1=1180|Y1=95|X2=1320|Y2=95
|RECORD=6|OwnerIndex=1|IndexInSheet=119|OwnerPartId=1|LocationCount=2|X1=1180|Y1=110|X2=1320|Y2=110
|RECORD=4|OwnerIndex=1|IndexInSheet=120|OwnerPartId=1|Location.X=1182|Location.Y=101|FontID=3|Text=CHK:
|RECORD=4|OwnerIndex=1|IndexInSheet=121|OwnerPartId=1|Location.X=1285|Location.Y=95|FontID=3|Text==CHK_APP_DATE
|RECORD=6|OwnerIndex=1|IndexInSheet=122|OwnerPartId=1|LocationCount=2|X1=1180|Y1=65|X2=1320|Y2=65
|RECORD=6|OwnerIndex=1|IndexInSheet=123|OwnerPartId=1|LocationCount=2|X1=1180|Y1=80|X2=1320|Y2=80
|RECORD=6|OwnerIndex=1|IndexInSheet=124|OwnerPartId=1|LocationCount=2|X1=1180|Y1=35|X2=1320|Y2=35
|RECORD=6|OwnerIndex=1|IndexInSheet=125|OwnerPartId=1|LocationCount=2|X1=1180|Y1=50|X2=1320|Y2=50
|RECORD=4|OwnerIndex=1|IndexInSheet=126|OwnerPartId=-1|Location.X=1204|Location.Y=82|FontID=3|Text=REFERENCE DOCUMENTS
|RECORD=4|OwnerIndex=1|IndexInSheet=127|OwnerPartId=1|Location.X=1182|Location.Y=71|FontID=3|Text=BOM:
|RECORD=4|OwnerIndex=1|IndexInSheet=128|OwnerPartId=1|Location.X=1183|Location.Y=56|FontID=3|Text=ASSY DWG:
|RECORD=4|OwnerIndex=1|IndexInSheet=129|OwnerPartId=1|Location.X=1182|Location.Y=41|FontID=3|Text=FAB DWG:
|RECORD=4|OwnerIndex=1|IndexInSheet=130|OwnerPartId=1|Location.X=1182|Location.Y=26|FontID=3|Text=PCB DWG:
|RECORD=4|OwnerIndex=1|IndexInSheet=131|OwnerPartId=-1|Location.X=1228|Location.Y=22|FontID=4|Text==PCB_DWG_NO
|RECORD=4|OwnerIndex=1|IndexInSheet=132|OwnerPartId=-1|Location.X=1228|Location.Y=37|FontID=4|Text==DOC_NO_FAB_DWG
|RECORD=4|OwnerIndex=1|IndexInSheet=133|OwnerPartId=-1|Location.X=1228|Location.Y=52|FontID=4|Text==DOC_NO_ASSY_DWG
|RECORD=4|OwnerIndex=1|IndexInSheet=134|OwnerPartId=-1|Location.X=1228|Location.Y=68|FontID=4|Text==DOC_NO_BOM
|RECORD=4|OwnerIndex=1|IndexInSheet=135|OwnerPartId=1|Location.X=1210|Location.Y=96|FontID=3|Text==CheckedBy
|RECORD=4|OwnerIndex=1|IndexInSheet=136|OwnerPartId=-1|Location.X=1591|Location.Y=104|FontID=7|Text==Item
|RECORD=6|OwnerIndex=1|IndexInSheet=137|OwnerPartId=-1|LineWidth=1|LocationCount=2|X1=1320|Y1=105|X2=1680|Y2=105
|RECORD=4|OwnerIndex=1|IndexInSheet=138|OwnerPartId=-1|Location.X=1322|Location.Y=115|Justification=3|FontID=3|Text=PROJECT REVISION:
|RECORD=4|OwnerIndex=1|IndexInSheet=139|OwnerPartId=-1|Location.X=1542|Location.Y=116|Justification=3|FontID=3|Text=DESIGN ITEM:
|RECORD=4|OwnerIndex=1|IndexInSheet=140|OwnerPartId=-1|Location.X=1432|Location.Y=116|Justification=3|FontID=3|Text=DOCUMENT REVISION:
|RECORD=6|OwnerIndex=1|IndexInSheet=141|OwnerPartId=-1|LocationCount=2|X1=1430|Y1=120|X2=1430|Y2=105
|RECORD=6|OwnerIndex=1|IndexInSheet=142|OwnerPartId=-1|LocationCount=2|X1=1541|Y1=120|X2=1541|Y2=105
|RECORD=4|OwnerIndex=1|IndexInSheet=143|OwnerPartId=-1|Location.X=1392|Location.Y=104|FontID=7|Text==VersionControl_ProjFolderRevNumber
|RECORD=4|OwnerIndex=1|IndexInSheet=144|OwnerPartId=-1|Location.X=1511|Location.Y=104|FontID=7|Text==VersionControl_RevNumber
|RECORD=6|OwnerIndex=1|IndexInSheet=145|OwnerPartId=-1|LineWidth=1|LocationCount=2|X1=1320|Y1=65|X2=1680|Y2=65
|RECORD=4|OwnerIndex=1|IndexInSheet=146|OwnerPartId=-1|Location.X=1662|Location.Y=41|FontID=7|Text==ItemRevision
|RECORD=30|OwnerIndex=1|IndexInSheet=147|OwnerPartId=-1|Location.X=1398|Location.Y=123|Corner.X=1558|Corner.X_Frac=41666|Corner.Y=158|KeepAspect=T|EmbedImage=T|FileName=Z:\Altium Project Template\Altium Logo\Altm black.jpg
|RECORD=17|IndexInSheet=1|OwnerPartId=-1|ShowNetName=T|Location.X=881|Location.Y=829|Orientation=1|Color=128|FontID=1|Text=+3.3V
|RECORD=17|IndexInSheet=2|OwnerPartId=-1|ShowNetName=T|Location.X=781|Location.Y=829|Orientation=1|Color=128|FontID=1|Text=+3.3V
|RECORD=17|IndexInSheet=3|OwnerPartId=-1|ShowNetName=T|Location.X=681|Location.Y=829|Orientation=1|Color=128|FontID=1|Text=+3.3V
|RECORD=17|IndexInSheet=4|OwnerPartId=-1|ShowNetName=T|Location.X=581|Location.Y=824|Orientation=1|Color=128|FontID=1|Text=+3.3V
|RECORD=17|IndexInSheet=5|OwnerPartId=-1|ShowNetName=T|Location.X=571|Location.Y=669|Orientation=2|Color=255|FontID=1|Text=LED1|IsCrossSheetConnector=T
|RECORD=17|IndexInSheet=6|OwnerPartId=-1|ShowNetName=T|Location.X=671|Location.Y=669|Orientation=2|Color=255|FontID=1|Text=LED2|IsCrossSheetConnector=T
|RECORD=17|IndexInSheet=7|OwnerPartId=-1|ShowNetName=T|Location.X=771|Location.Y=669|Orientation=2|Color=255|FontID=1|Text=LED3|IsCrossSheetConnector=T
|RECORD=17|IndexInSheet=8|OwnerPartId=-1|ShowNetName=T|Location.X=871|Location.Y=669|Orientation=2|Color=255|FontID=1|Text=LED4|IsCrossSheetConnector=T
|RECORD=4|IndexInSheet=9|OwnerPartId=-1|Location.X=631|Location.Y=849|Color=8388608|FontID=6|Text=SYSTEM STATUS LEDS
|RECORD=1|LibReference=RES|ComponentDescription=ERJ-3EKF2000V|PartCount=2|DisplayModeCount=2|IndexInSheet=10|OwnerPartId=-1|Location.X=571|Location.Y=699|Orientation=1|CurrentPartId=1|SourceLibraryName=Altium Content Vault|TargetFileName=*|AreaColor=11599871|Color=128|PartIDLocked=F|DesignItemId=CMP-2000-00316-1|AllPinCount=2
|RECORD=2|OwnerIndex=159|OwnerPartId=1|OwnerPartDisplayMode=1|FormalType=1|Electrical=4|PinConglomerate=33|PinLength=10|Location.X=581|Location.Y=719|Name=2|Designator=2|PinPropagationDelay=0.000000E+000
|RECORD=2|OwnerIndex=159|OwnerPartId=1|OwnerPartDisplayMode=1|FormalType=1|Electrical=4|PinConglomerate=35|PinLength=10|Location.X=581|Location.Y=699|Name=1|Designator=1|PinPropagationDelay=0.000000E+000
|RECORD=14|OwnerIndex=159|IsNotAccesible=T|IndexInSheet=2|OwnerPartId=1|OwnerPartDisplayMode=1|Location.X=577|Location.Y=699|Corner.X=585|Corner.Y=719|LineWidth=1|Color=16711680|AreaColor=11599871
|RECORD=2|OwnerIndex=159|OwnerPartId=1|FormalType=1|Electrical=4|PinConglomerate=33|PinLength=10|Location.X=581|Location.Y=719|Name=2|Designator=2|PinPropagationDelay=0.000000E+000
|RECORD=2|OwnerIndex=159|OwnerPartId=1|FormalType=1|Electrical=4|PinConglomerate=35|PinLength=10|Location.X=581|Location.Y=699|Name=1|Designator=1|PinPropagationDelay=0.000000E+000
|RECORD=6|OwnerIndex=159|IsNotAccesible=T|IndexInSheet=5|OwnerPartId=1|LineWidth=1|Color=16711680|LocationCount=10|X1=581|Y1=719|X2=581|Y2=715|X3=583|Y3=714|X4=579|Y4=712|X5=583|Y5=710|X6=579|Y6=708|X7=583|Y7=706|X8=579|Y8=704|X9=581|Y9=703|X10=581|Y10=699
|RECORD=41|OwnerIndex=159|IndexInSheet=6|OwnerPartId=-1|Location.X=578|Location.Y=731|Color=8388608|FontID=1|IsHidden=T|Text=Panasonic|Name=Manufacturer
|RECORD=41|OwnerIndex=159|IndexInSheet=7|OwnerPartId=-1|Location.X=578|Location.Y=731|Color=8388608|FontID=1|IsHidden=T|Text=ERJ-3EKF2000V|Name=Part Number
|RECORD=34|OwnerIndex=159|IndexInSheet=-1|OwnerPartId=-1|Location.X=584|Location.Y=710|Color=8388608|FontID=1|Text=R35|Name=Designator|ReadOnlyState=1
|RECORD=41|OwnerIndex=159|IndexInSheet=-1|OwnerPartId=-1|Location.X=584|Location.Y=700|Color=8388608|FontID=1|Text=200 OHM|Name=Comment
|RECORD=44|OwnerIndex=159
|RECORD=45|OwnerIndex=174|IndexInSheet=-1|Description=Chip Resistor, 2-Leads, Body 1.60x0.80mm, IPC Medium Density|UseComponentLibrary=T|ModelName=RESC1608X55X30NL15T15|ModelType=PCBLIB|DatafileCount=1|ModelDatafileEntity0=RESC1608X55X30NL15T15|ModelDatafileKind0=PCBLib|IsCurrent=T|DatalinksLocked=T|DatabaseDatalinksLocked=T
|RECORD=46|OwnerIndex=175
|RECORD=48|OwnerIndex=175
|RECORD=41|OwnerIndex=177|IndexInSheet=-1|OwnerPartId=-1|Color=8388608|FontID=1|Text=2D|Name=Available Preview Images
|RECORD=45|OwnerIndex=174|IndexInSheet=-1|Description=Chip Resistor, 2-Leads, Body 1.60x0.80mm, IPC Low Density|UseComponentLibrary=T|ModelName=RESC1608X55X30ML15T15|ModelType=PCBLIB|DatafileCount=1|ModelDatafileEntity0=RESC1608X55X30ML15T15|ModelDatafileKind0=PCBLib|DatalinksLocked=T|DatabaseDatalinksLocked=T
|RECORD=46|OwnerIndex=179
|RECORD=48|OwnerIndex=179
|RECORD=41|OwnerIndex=181|IndexInSheet=-1|OwnerPartId=-1|Color=8388608|FontID=1|Text=2D|Name=Available Preview Images
|RECORD=45|OwnerIndex=174|IndexInSheet=-1|Description=Chip Resistor, 2-Leads, Body 1.60x0.80mm, IPC High Density|UseComponentLibrary=T|ModelName=RESC1608X55X30LL15T15|ModelType=PCBLIB|DatafileCount=1|ModelDatafileEntity0=RESC1608X55X30LL15T15|ModelDatafileKind0=PCBLib|DatalinksLocked=T|DatabaseDatalinksLocked=T
|RECORD=46|OwnerIndex=183
|RECORD=48|OwnerIndex=183
|RECORD=41|OwnerIndex=185|IndexInSheet=-1|OwnerPartId=-1|Color=8388608|FontID=1|Text=2D|Name=Available Preview Images
|RECORD=1|LibReference=RES|ComponentDescription=ERJ-3EKF2000V|PartCount=2|DisplayModeCount=2|IndexInSheet=11|OwnerPartId=-1|Location.X=671|Location.Y=699|Orientation=1|CurrentPartId=1|SourceLibraryName=Altium Content Vault|TargetFileName=*|AreaColor=11599871|Color=128|PartIDLocked=F|DesignItemId=CMP-2000-00316-1|AllPinCount=2
|RECORD=2|OwnerIndex=187|OwnerPartId=1|OwnerPartDisplayMode=1|FormalType=1|Electrical=4|PinConglomerate=33|PinLength=10|Location.X=681|Location.Y=719|Name=2|Designator=2|PinPropagationDelay=0.000000E+000
|RECORD=2|OwnerIndex=187|OwnerPartId=1|OwnerPartDisplayMode=1|FormalType=1|Electrical=4|PinConglomerate=35|PinLength=10|Location.X=681|Location.Y=699|Name=1|Designator=1|PinPropagationDelay=0.000000E+000
|RECORD=14|OwnerIndex=187|IsNotAccesible=T|IndexInSheet=2|OwnerPartId=1|OwnerPartDisplayMode=1|Location.X=677|Location.Y=699|Corner.X=685|Corner.Y=719|LineWidth=1|Color=16711680|AreaColor=11599871
|RECORD=2|OwnerIndex=187|OwnerPartId=1|FormalType=1|Electrical=4|PinConglomerate=33|PinLength=10|Location.X=681|Location.Y=719|Name=2|Designator=2|PinPropagationDelay=0.000000E+000
|RECORD=2|OwnerIndex=187|OwnerPartId=1|FormalType=1|Electrical=4|PinConglomerate=35|PinLength=10|Location.X=681|Location.Y=699|Name=1|Designator=1|PinPropagationDelay=0.000000E+000
|RECORD=6|OwnerIndex=187|IsNotAccesible=T|IndexInSheet=5|OwnerPartId=1|LineWidth=1|Color=16711680|LocationCount=10|X1=681|Y1=719|X2=681|Y2=715|X3=683|Y3=714|X4=679|Y4=712|X5=683|Y5=710|X6=679|Y6=708|X7=683|Y7=706|X8=679|Y8=704|X9=681|Y9=703|X10=681|Y10=699
|RECORD=41|OwnerIndex=187|IndexInSheet=6|OwnerPartId=-1|Location.X=678|Location.Y=731|Color=8388608|FontID=1|IsHidden=T|Text=Panasonic|Name=Manufacturer
|RECORD=41|OwnerIndex=187|IndexInSheet=7|OwnerPartId=-1|Location.X=678|Location.Y=731|Color=8388608|FontID=1|IsHidden=T|Text=ERJ-3EKF2000V|Name=Part Number
|RECORD=34|OwnerIndex=187|IndexInSheet=-1|OwnerPartId=-1|Location.X=684|Location.Y=710|Color=8388608|FontID=1|Text=R36|Name=Designator|ReadOnlyState=1
|RECORD=41|OwnerIndex=187|IndexInSheet=-1|OwnerPartId=-1|Location.X=684|Location.Y=700|Color=8388608|FontID=1|Text=200 OHM|Name=Comment
|RECORD=44|OwnerIndex=187
|RECORD=45|OwnerIndex=202|IndexInSheet=-1|Description=Chip Resistor, 2-Leads, Body 1.60x0.80mm, IPC Medium Density|UseComponentLibrary=T|ModelName=RESC1608X55X30NL15T15|ModelType=PCBLIB|DatafileCount=1|ModelDatafileEntity0=RESC1608X55X30NL15T15|ModelDatafileKind0=PCBLib|IsCurrent=T|DatalinksLocked=T|DatabaseDatalinksLocked=T
|RECORD=46|OwnerIndex=203
|RECORD=48|OwnerIndex=203
|RECORD=41|OwnerIndex=205|IndexInSheet=-1|OwnerPartId=-1|Color=8388608|FontID=1|Text=2D|Name=Available Preview Images
|RECORD=45|OwnerIndex=202|IndexInSheet=-1|Description=Chip Resistor, 2-Leads, Body 1.60x0.80mm, IPC Low Density|UseComponentLibrary=T|ModelName=RESC1608X55X30ML15T15|ModelType=PCBLIB|DatafileCount=1|ModelDatafileEntity0=RESC1608X55X30ML15T15|ModelDatafileKind0=PCBLib|DatalinksLocked=T|DatabaseDatalinksLocked=T
|RECORD=46|OwnerIndex=207
|RECORD=48|OwnerIndex=207
|RECORD=41|OwnerIndex=209|IndexInSheet=-1|OwnerPartId=-1|Color=8388608|FontID=1|Text=2D|Name=Available Preview Images
|RECORD=45|OwnerIndex=202|IndexInSheet=-1|Description=Chip Resistor, 2-Leads, Body 1.60x0.80mm, IPC High Density|UseComponentLibrary=T|ModelName=RESC1608X55X30LL15T15|ModelType=PCBLIB|DatafileCount=1|ModelDatafileEntity0=RESC1608X55X30LL15T15|ModelDatafileKind0=PCBLib|DatalinksLocked=T|DatabaseDatalinksLocked=T
|RECORD=46|OwnerIndex=211
|RECORD=48|OwnerIndex=211
|RECORD=41|OwnerIndex=213|IndexInSheet=-1|OwnerPartId=-1|Color=8388608|FontID=1|Text=2D|Name=Available Preview Images
|RECORD=1|LibReference=RES|ComponentDescription=ERJ-3EKF2000V|PartCount=2|DisplayModeCount=2|IndexInSheet=12|OwnerPartId=-1|Location.X=771|Location.Y=699|Orientation=1|CurrentPartId=1|SourceLibraryName=Altium Content Vault|TargetFileName=*|AreaColor=11599871|Color=128|PartIDLocked=F|DesignItemId=CMP-2000-00316-1|AllPinCount=2
|RECORD=2|OwnerIndex=215|OwnerPartId=1|OwnerPartDisplayMode=1|FormalType=1|Electrical=4|PinConglomerate=33|PinLength=10|Location.X=781|Location.Y=719|Name=2|Designator=2|PinPropagationDelay=0.000000E+000
|RECORD=2|OwnerIndex=215|OwnerPartId=1|OwnerPartDisplayMode=1|FormalType=1|Electrical=4|PinConglomerate=35|PinLength=10|Location.X=781|Location.Y=699|Name=1|Designator=1|PinPropagationDelay=0.000000E+000
|RECORD=14|OwnerIndex=215|IsNotAccesible=T|IndexInSheet=2|OwnerPartId=1|OwnerPartDisplayMode=1|Location.X=777|Location.Y=699|Corner.X=785|Corner.Y=719|LineWidth=1|Color=16711680|AreaColor=11599871
|RECORD=2|OwnerIndex=215|OwnerPartId=1|FormalType=1|Electrical=4|PinConglomerate=33|PinLength=10|Location.X=781|Location.Y=719|Name=2|Designator=2|PinPropagationDelay=0.000000E+000
|RECORD=2|OwnerIndex=215|OwnerPartId=1|FormalType=1|Electrical=4|PinConglomerate=35|PinLength=10|Location.X=781|Location.Y=699|Name=1|Designator=1|PinPropagationDelay=0.000000E+000
|RECORD=6|OwnerIndex=215|IsNotAccesible=T|IndexInSheet=5|OwnerPartId=1|LineWidth=1|Color=16711680|LocationCount=10|X1=781|Y1=719|X2=781|Y2=715|X3=783|Y3=714|X4=779|Y4=712|X5=783|Y5=710|X6=779|Y6=708|X7=783|Y7=706|X8=779|Y8=704|X9=781|Y9=703|X10=781|Y10=699
|RECORD=41|OwnerIndex=215|IndexInSheet=6|OwnerPartId=-1|Location.X=778|Location.Y=731|Color=8388608|FontID=1|IsHidden=T|Text=Panasonic|Name=Manufacturer
|RECORD=41|OwnerIndex=215|IndexInSheet=7|OwnerPartId=-1|Location.X=778|Location.Y=731|Color=8388608|FontID=1|IsHidden=T|Text=ERJ-3EKF2000V|Name=Part Number
|RECORD=34|OwnerIndex=215|IndexInSheet=-1|OwnerPartId=-1|Location.X=784|Location.Y=710|Color=8388608|FontID=1|Text=R38|Name=Designator|ReadOnlyState=1
|RECORD=41|OwnerIndex=215|IndexInSheet=-1|OwnerPartId=-1|Location.X=784|Location.Y=700|Color=8388608|FontID=1|Text=200 OHM|Name=Comment
|RECORD=44|OwnerIndex=215
|RECORD=45|OwnerIndex=230|IndexInSheet=-1|Description=Chip Resistor, 2-Leads, Body 1.60x0.80mm, IPC Medium Density|UseComponentLibrary=T|ModelName=RESC1608X55X30NL15T15|ModelType=PCBLIB|DatafileCount=1|ModelDatafileEntity0=RESC1608X55X30NL15T15|ModelDatafileKind0=PCBLib|IsCurrent=T|DatalinksLocked=T|DatabaseDatalinksLocked=T
|RECORD=46|OwnerIndex=231
|RECORD=48|OwnerIndex=231
|RECORD=41|OwnerIndex=233|IndexInSheet=-1|OwnerPartId=-1|Color=8388608|FontID=1|Text=2D|Name=Available Preview Images
|RECORD=45|OwnerIndex=230|IndexInSheet=-1|Description=Chip Resistor, 2-Leads, Body 1.60x0.80mm, IPC Low Density|UseComponentLibrary=T|ModelName=RESC1608X55X30ML15T15|ModelType=PCBLIB|DatafileCount=1|ModelDatafileEntity0=RESC1608X55X30ML15T15|ModelDatafileKind0=PCBLib|DatalinksLocked=T|DatabaseDatalinksLocked=T
|RECORD=46|OwnerIndex=235
|RECORD=48|OwnerIndex=235
|RECORD=41|OwnerIndex=237|IndexInSheet=-1|OwnerPartId=-1|Color=8388608|FontID=1|Text=2D|Name=Available Preview Images
|RECORD=45|OwnerIndex=230|IndexInSheet=-1|Description=Chip Resistor, 2-Leads, Body 1.60x0.80mm, IPC High Density|UseComponentLibrary=T|ModelName=RESC1608X55X30LL15T15|ModelType=PCBLIB|DatafileCount=1|ModelDatafileEntity0=RESC1608X55X30LL15T15|ModelDatafileKind0=PCBLib|DatalinksLocked=T|DatabaseDatalinksLocked=T
|RECORD=46|OwnerIndex=239
|RECORD=48|OwnerIndex=239
|RECORD=41|OwnerIndex=241|IndexInSheet=-1|OwnerPartId=-1|Color=8388608|FontID=1|Text=2D|Name=Available Preview Images
|RECORD=1|LibReference=RES|ComponentDescription=ERJ-3EKF2000V|PartCount=2|DisplayModeCount=2|IndexInSheet=13|OwnerPartId=-1|Location.X=871|Location.Y=699|Orientation=1|CurrentPartId=1|SourceLibraryName=Altium Content Vault|TargetFileName=*|AreaColor=11599871|Color=128|PartIDLocked=F|DesignItemId=CMP-2000-00316-1|AllPinCount=2
|RECORD=2|OwnerIndex=243|OwnerPartId=1|OwnerPartDisplayMode=1|FormalType=1|Electrical=4|PinConglomerate=33|PinLength=10|Location.X=881|Location.Y=719|Name=2|Designator=2|PinPropagationDelay=0.000000E+000
|RECORD=2|OwnerIndex=243|OwnerPartId=1|OwnerPartDisplayMode=1|FormalType=1|Electrical=4|PinConglomerate=35|PinLength=10|Location.X=881|Location.Y=699|Name=1|Designator=1|PinPropagationDelay=0.000000E+000
|RECORD=14|OwnerIndex=243|IsNotAccesible=T|IndexInSheet=2|OwnerPartId=1|OwnerPartDisplayMode=1|Location.X=877|Location.Y=699|Corner.X=885|Corner.Y=719|LineWidth=1|Color=16711680|AreaColor=11599871
|RECORD=2|OwnerIndex=243|OwnerPartId=1|FormalType=1|Electrical=4|PinConglomerate=33|PinLength=10|Location.X=881|Location.Y=719|Name=2|Designator=2|PinPropagationDelay=0.000000E+000
|RECORD=2|OwnerIndex=243|OwnerPartId=1|FormalType=1|Electrical=4|PinConglomerate=35|PinLength=10|Location.X=881|Location.Y=699|Name=1|Designator=1|PinPropagationDelay=0.000000E+000
|RECORD=6|OwnerIndex=243|IsNotAccesible=T|IndexInSheet=5|OwnerPartId=1|LineWidth=1|Color=16711680|LocationCount=10|X1=881|Y1=719|X2=881|Y2=715|X3=883|Y3=714|X4=879|Y4=712|X5=883|Y5=710|X6=879|Y6=708|X7=883|Y7=706|X8=879|Y8=704|X9=881|Y9=703|X10=881|Y10=699
|RECORD=41|OwnerIndex=243|IndexInSheet=6|OwnerPartId=-1|Location.X=878|Location.Y=731|Color=8388608|FontID=1|IsHidden=T|Text=Panasonic|Name=Manufacturer
|RECORD=41|OwnerIndex=243|IndexInSheet=7|OwnerPartId=-1|Location.X=878|Location.Y=731|Color=8388608|FontID=1|IsHidden=T|Text=ERJ-3EKF2000V|Name=Part Number
|RECORD=34|OwnerIndex=243|IndexInSheet=-1|OwnerPartId=-1|Location.X=884|Location.Y=710|Color=8388608|FontID=1|Text=R39|Name=Designator|ReadOnlyState=1
|RECORD=41|OwnerIndex=243|IndexInSheet=-1|OwnerPartId=-1|Location.X=884|Location.Y=700|Color=8388608|FontID=1|Text=200 OHM|Name=Comment
|RECORD=44|OwnerIndex=243
|RECORD=45|OwnerIndex=258|IndexInSheet=-1|Description=Chip Resistor, 2-Leads, Body 1.60x0.80mm, IPC Medium Density|UseComponentLibrary=T|ModelName=RESC1608X55X30NL15T15|ModelType=PCBLIB|DatafileCount=1|ModelDatafileEntity0=RESC1608X55X30NL15T15|ModelDatafileKind0=PCBLib|IsCurrent=T|DatalinksLocked=T|DatabaseDatalinksLocked=T
|RECORD=46|OwnerIndex=259
|RECORD=48|OwnerIndex=259
|RECORD=41|OwnerIndex=261|IndexInSheet=-1|OwnerPartId=-1|Color=8388608|FontID=1|Text=2D|Name=Available Preview Images
|RECORD=45|OwnerIndex=258|IndexInSheet=-1|Description=Chip Resistor, 2-Leads, Body 1.60x0.80mm, IPC Low Density|UseComponentLibrary=T|ModelName=RESC1608X55X30ML15T15|ModelType=PCBLIB|DatafileCount=1|ModelDatafileEntity0=RESC1608X55X30ML15T15|ModelDatafileKind0=PCBLib|DatalinksLocked=T|DatabaseDatalinksLocked=T
|RECORD=46|OwnerIndex=263
|RECORD=48|OwnerIndex=263
|RECORD=41|OwnerIndex=265|IndexInSheet=-1|OwnerPartId=-1|Color=8388608|FontID=1|Text=2D|Name=Available Preview Images
|RECORD=45|OwnerIndex=258|IndexInSheet=-1|Description=Chip Resistor, 2-Leads, Body 1.60x0.80mm, IPC High Density|UseComponentLibrary=T|ModelName=RESC1608X55X30LL15T15|ModelType=PCBLIB|DatafileCount=1|ModelDatafileEntity0=RESC1608X55X30LL15T15|ModelDatafileKind0=PCBLib|DatalinksLocked=T|DatabaseDatalinksLocked=T
|RECORD=46|OwnerIndex=267
|RECORD=48|OwnerIndex=267
|RECORD=41|OwnerIndex=269|IndexInSheet=-1|OwnerPartId=-1|Color=8388608|FontID=1|Text=2D|Name=Available Preview Images
|RECORD=1|LibReference=155124M173200|ComponentDescription=LED (Multiple)|PartCount=2|DisplayModeCount=1|IndexInSheet=14|OwnerPartId=-1|Location.X=1194|Location.Y=515|IsMirrored=T|CurrentPartId=1|LibraryPath=*|SourceLibraryName=SamacSys.SchLib|TargetFileName=*|AreaColor=11599871|Color=128|PartIDLocked=T|DesignItemId=155124M173200|AllPinCount=4
|RECORD=41|OwnerIndex=271|OwnerPartId=-1|Location.X=1112|Location.Y=515|Color=8388608|FontID=5|IsHidden=T|Text=https://www.mouser.com/ds/2/445/155124M173200-1113601.pdf|Name=Datasheet Link|IsMirrored=T
|RECORD=41|OwnerIndex=271|IndexInSheet=1|OwnerPartId=-1|Location.X=1112|Location.Y=515|Color=8388608|FontID=1|IsHidden=T|Text=Wurth Elektronik|Name=Manufacturer_Name|IsMirrored=T
|RECORD=41|OwnerIndex=271|IndexInSheet=2|OwnerPartId=-1|Location.X=1112|Location.Y=515|Color=8388608|FontID=1|IsHidden=T|Text=155124M173200|Name=Manufacturer_Part_Number|IsMirrored=T
|RECORD=41|OwnerIndex=271|IndexInSheet=3|OwnerPartId=-1|Location.X=1112|Location.Y=515|Color=8388608|FontID=1|IsHidden=T|Text=710-155124M173200|Name=Mouser Part Number|IsMirrored=T
|RECORD=41|OwnerIndex=271|IndexInSheet=4|OwnerPartId=-1|Location.X=1112|Location.Y=515|Color=8388608|FontID=5|IsHidden=T|Text=https://www.mouser.co.uk/ProductDetail/Wurth-Elektronik/155124M173200?qs=5aG0NVq1C4xPhoUU07x4gQ%3D%3D|Name=Mouser Price/Stock|IsMirrored=T
|RECORD=41|OwnerIndex=271|IndexInSheet=5|OwnerPartId=-1|Location.X=1112|Location.Y=515|Color=8388608|FontID=1|IsHidden=T|Name=Arrow Part Number|IsMirrored=T
|RECORD=41|OwnerIndex=271|IndexInSheet=6|OwnerPartId=-1|Location.X=1112|Location.Y=515|Color=8388608|FontID=1|IsHidden=T|Name=Arrow Price/Stock|IsMirrored=T
|RECORD=14|OwnerIndex=271|IsNotAccesible=T|IndexInSheet=7|OwnerPartId=1|Location.X=1134|Location.Y=475|Corner.X=1194|Corner.Y=515|LineWidth=1|Color=128|AreaColor=11599871|IsSolid=T
|RECORD=2|OwnerIndex=271|OwnerPartId=1|FormalType=1|Electrical=7|PinConglomerate=56|PinLength=20|Location.X=1194|Location.Y=505|Name=ANODE|Designator=1|SwapIDPart=Ž&Ž||PinPropagationDelay=0.000000E+000
|RECORD=2|OwnerIndex=271|OwnerPartId=1|FormalType=1|Electrical=2|PinConglomerate=58|PinLength=20|Location.X=1134|Location.Y=485|Name=B|Designator=2|SwapIDPart=Ž&Ž||PinPropagationDelay=0.000000E+000
|RECORD=2|OwnerIndex=271|OwnerPartId=1|FormalType=1|Electrical=2|PinConglomerate=58|PinLength=20|Location.X=1134|Location.Y=495|Name=G|Designator=3|SwapIDPart=Ž&Ž||PinPropagationDelay=0.000000E+000
|RECORD=2|OwnerIndex=271|OwnerPartId=1|FormalType=1|Electrical=2|PinConglomerate=58|PinLength=20|Location.X=1134|Location.Y=505|Name=R|Designator=4|SwapIDPart=Ž&Ž||PinPropagationDelay=0.000000E+000
|RECORD=34|OwnerIndex=271|IndexInSheet=-1|OwnerPartId=-1|Location.X=1134|Location.Y=515|Color=8388608|FontID=1|Text=D13|Name=Designator|ReadOnlyState=1|IsMirrored=T
|RECORD=41|OwnerIndex=271|IndexInSheet=-1|OwnerPartId=-1|Location.X=1134|Location.Y=465|Color=8388608|FontID=1|Text=155124M173200|Name=Comment|IsMirrored=T
|RECORD=44|OwnerIndex=271
|RECORD=45|OwnerIndex=290|IndexInSheet=-1|ModelName=155124M173200|ModelType=PCBLIB|DatafileCount=1|ModelDatafile0=C:\Users\<user>\Documents\AltiumLL\SamacSys.PcbLib|ModelDatafileEntity0=155124M173200|ModelDatafileKind0=PCBLIB|IsCurrent=T
|RECORD=46|OwnerIndex=291
|RECORD=48|OwnerIndex=291
|RECORD=1|LibReference=155124M173200|ComponentDescription=LED (Multiple)|PartCount=2|DisplayModeCount=1|IndexInSheet=15|OwnerPartId=-1|Location.X=1194|Location.Y=455|IsMirrored=T|CurrentPartId=1|LibraryPath=*|SourceLibraryName=SamacSys.SchLib|TargetFileName=*|AreaColor=11599871|Color=128|PartIDLocked=T|DesignItemId=155124M173200|AllPinCount=4
|RECORD=41|OwnerIndex=294|OwnerPartId=-1|Location.X=1112|Location.Y=455|Color=8388608|FontID=5|IsHidden=T|Text=https://www.mouser.com/ds/2/445/155124M173200-1113601.pdf|Name=Datasheet Link|IsMirrored=T
|RECORD=41|OwnerIndex=294|IndexInSheet=1|OwnerPartId=-1|Location.X=1112|Location.Y=455|Color=8388608|FontID=1|IsHidden=T|Text=Wurth Elektronik|Name=Manufacturer_Name|IsMirrored=T
|RECORD=41|OwnerIndex=294|IndexInSheet=2|OwnerPartId=-1|Location.X=1112|Location.Y=455|Color=8388608|FontID=1|IsHidden=T|Text=155124M173200|Name=Manufacturer_Part_Number|IsMirrored=T
|RECORD=41|OwnerIndex=294|IndexInSheet=3|OwnerPartId=-1|Location.X=1112|Location.Y=455|Color=8388608|FontID=1|IsHidden=T|Text=710-155124M173200|Name=Mouser Part Number|IsMirrored=T
|RECORD=41|OwnerIndex=294|IndexInSheet=4|OwnerPartId=-1|Location.X=1112|Location.Y=455|Color=8388608|FontID=5|IsHidden=T|Text=https://www.mouser.co.uk/ProductDetail/Wurth-Elektronik/155124M173200?qs=5aG0NVq1C4xPhoUU07x4gQ%3D%3D|Name=Mouser Price/Stock|IsMirrored=T
|RECORD=41|OwnerIndex=294|IndexInSheet=5|OwnerPartId=-1|Location.X=1112|Location.Y=455|Color=8388608|FontID=1|IsHidden=T|Name=Arrow Part Number|IsMirrored=T
|RECORD=41|OwnerIndex=294|IndexInSheet=6|OwnerPartId=-1|Location.X=1112|Location.Y=455|Color=8388608|FontID=1|IsHidden=T|Name=Arrow Price/Stock|IsMirrored=T
|RECORD=14|OwnerIndex=294|IsNotAccesible=T|IndexInSheet=7|OwnerPartId=1|Location.X=1134|Location.Y=415|Corner.X=1194|Corner.Y=455|LineWidth=1|Color=128|AreaColor=11599871|IsSolid=T
|RECORD=2|OwnerIndex=294|OwnerPartId=1|FormalType=1|Electrical=7|PinConglomerate=56|PinLength=20|Location.X=1194|Location.Y=445|Name=ANODE|Designator=1|SwapIDPart=Ž&Ž||PinPropagationDelay=0.000000E+000
|RECORD=2|OwnerIndex=294|OwnerPartId=1|FormalType=1|Electrical=2|PinConglomerate=58|PinLength=20|Location.X=1134|Location.Y=425|Name=B|Designator=2|SwapIDPart=Ž&Ž||PinPropagationDelay=0.000000E+000
|RECORD=2|OwnerIndex=294|OwnerPartId=1|FormalType=1|Electrical=2|PinConglomerate=58|PinLength=20|Location.X=1134|Location.Y=435|Name=G|Designator=3|SwapIDPart=Ž&Ž||PinPropagationDelay=0.000000E+000
|RECORD=2|OwnerIndex=294|OwnerPartId=1|FormalType=1|Electrical=2|PinConglomerate=58|PinLength=20|Location.X=1134|Location.Y=445|Name=R|Designator=4|SwapIDPart=Ž&Ž||PinPropagationDelay=0.000000E+000
|RECORD=34|OwnerIndex=294|IndexInSheet=-1|OwnerPartId=-1|Location.X=1134|Location.Y=455|Color=8388608|FontID=1|Text=D14|Name=Designator|ReadOnlyState=1|IsMirrored=T
|RECORD=41|OwnerIndex=294|IndexInSheet=-1|OwnerPartId=-1|Location.X=1134|Location.Y=405|Color=8388608|FontID=1|Text=155124M173200|Name=Comment|IsMirrored=T
|RECORD=44|OwnerIndex=294
|RECORD=45|OwnerIndex=313|IndexInSheet=-1|ModelName=155124M173200|ModelType=PCBLIB|DatafileCount=1|ModelDatafile0=C:\Users\<user>\Documents\AltiumLL\SamacSys.PcbLib|ModelDatafileEntity0=155124M173200|ModelDatafileKind0=PCBLIB|IsCurrent=T
|RECORD=46|OwnerIndex=314
|RECORD=48|OwnerIndex=314
|RECORD=1|LibReference=155124M173200|ComponentDescription=LED (Multiple)|PartCount=2|DisplayModeCount=1|IndexInSheet=16|OwnerPartId=-1|Location.X=1194|Location.Y=395|IsMirrored=T|CurrentPartId=1|LibraryPath=*|SourceLibraryName=SamacSys.SchLib|TargetFileName=*|AreaColor=11599871|Color=128|PartIDLocked=T|DesignItemId=155124M173200|AllPinCount=4
|RECORD=41|OwnerIndex=317|OwnerPartId=-1|Location.X=1112|Location.Y=395|Color=8388608|FontID=5|IsHidden=T|Text=https://www.mouser.com/ds/2/445/155124M173200-1113601.pdf|Name=Datasheet Link|IsMirrored=T
|RECORD=41|OwnerIndex=317|IndexInSheet=1|OwnerPartId=-1|Location.X=1112|Location.Y=395|Color=8388608|FontID=1|IsHidden=T|Text=Wurth Elektronik|Name=Manufacturer_Name|IsMirrored=T
|RECORD=41|OwnerIndex=317|IndexInSheet=2|OwnerPartId=-1|Location.X=1112|Location.Y=395|Color=8388608|FontID=1|IsHidden=T|Text=155124M173200|Name=Manufacturer_Part_Number|IsMirrored=T
|RECORD=41|OwnerIndex=317|IndexInSheet=3|OwnerPartId=-1|Location.X=1112|Location.Y=395|Color=8388608|FontID=1|IsHidden=T|Text=710-155124M173200|Name=Mouser Part Number|IsMirrored=T
|RECORD=41|OwnerIndex=317|IndexInSheet=4|OwnerPartId=-1|Location.X=1112|Location.Y=395|Color=8388608|FontID=5|IsHidden=T|Text=https://www.mouser.co.uk/ProductDetail/Wurth-Elektronik/155124M173200?qs=5aG0NVq1C4xPhoUU07x4gQ%3D%3D|Name=Mouser Price/Stock|IsMirrored=T
|RECORD=41|OwnerIndex=317|IndexInSheet=5|OwnerPartId=-1|Location.X=1112|Location.Y=395|Color=8388608|FontID=1|IsHidden=T|Name=Arrow Part Number|IsMirrored=T
|RECORD=41|OwnerIndex=317|IndexInSheet=6|OwnerPartId=-1|Location.X=1112|Location.Y=395|Color=8388608|FontID=1|IsHidden=T|Name=Arrow Price/Stock|IsMirrored=T
|RECORD=14|OwnerIndex=317|IsNotAccesible=T|IndexInSheet=7|OwnerPartId=1|Location.X=1134|Location.Y=355|Corner.X=1194|Corner.Y=395|LineWidth=1|Color=128|AreaColor=11599871|IsSolid=T
|RECORD=2|OwnerIndex=317|OwnerPartId=1|FormalType=1|Electrical=7|PinConglomerate=56|PinLength=20|Location.X=1194|Location.Y=385|Name=ANODE|Designator=1|SwapIDPart=Ž&Ž||PinPropagationDelay=0.000000E+000
|RECORD=2|OwnerIndex=317|OwnerPartId=1|FormalType=1|Electrical=2|PinConglomerate=58|PinLength=20|Location.X=1134|Location.Y=365|Name=B|Designator=2|SwapIDPart=Ž&Ž||PinPropagationDelay=0.000000E+000
|RECORD=2|OwnerIndex=317|OwnerPartId=1|FormalType=1|Electrical=2|PinConglomerate=58|PinLength=20|Location.X=1134|Location.Y=375|Name=G|Designator=3|SwapIDPart=Ž&Ž||PinPropagationDelay=0.000000E+000
|RECORD=2|OwnerIndex=317|OwnerPartId=1|FormalType=1|Electrical=2|PinConglomerate=58|PinLength=20|Location.X=1134|Location.Y=385|Name=R|Designator=4|SwapIDPart=Ž&Ž||PinPropagationDelay=0.000000E+000
|RECORD=34|OwnerIndex=317|IndexInSheet=-1|OwnerPartId=-1|Location.X=1134|Location.Y=395|Color=8388608|FontID=1|Text=D15|Name=Designator|ReadOnlyState=1|IsMirrored=T
|RECORD=41|OwnerIndex=317|IndexInSheet=-1|OwnerPartId=-1|Location.X=1134|Location.Y=345|Color=8388608|FontID=1|Text=155124M173200|Name=Comment|IsMirrored=T
|RECORD=44|OwnerIndex=317
|RECORD=45|OwnerIndex=336|IndexInSheet=-1|ModelName=155124M173200|ModelType=PCBLIB|DatafileCount=1|ModelDatafile0=C:\Users\<user>\Documents\AltiumLL\SamacSys.PcbLib|ModelDatafileEntity0=155124M173200|ModelDatafileKind0=PCBLIB|IsCurrent=T
|RECORD=46|OwnerIndex=337
|RECORD=48|OwnerIndex=337
|RECORD=1|LibReference=155124M173200|ComponentDescription=LED (Multiple)|PartCount=2|DisplayModeCount=1|IndexInSheet=17|OwnerPartId=-1|Location.X=1194|Location.Y=335|IsMirrored=T|CurrentPartId=1|LibraryPath=*|SourceLibraryName=SamacSys.SchLib|TargetFileName=*|AreaColor=11599871|Color=128|PartIDLocked=T|DesignItemId=155124M173200|AllPinCount=4
|RECORD=41|OwnerIndex=340|OwnerPartId=-1|Location.X=1112|Location.Y=335|Color=8388608|FontID=5|IsHidden=T|Text=https://www.mouser.com/ds/2/445/155124M173200-1113601.pdf|Name=Datasheet Link|IsMirrored=T
|RECORD=41|OwnerIndex=340|IndexInSheet=1|OwnerPartId=-1|Location.X=1112|Location.Y=335|Color=8388608|FontID=1|IsHidden=T|Text=Wurth Elektronik|Name=Manufacturer_Name|IsMirrored=T
|RECORD=41|OwnerIndex=340|IndexInSheet=2|OwnerPartId=-1|Location.X=1112|Location.Y=335|Color=8388608|FontID=1|IsHidden=T|Text=155124M173200|Name=Manufacturer_Part_Number|IsMirrored=T
|RECORD=41|OwnerIndex=340|IndexInSheet=3|OwnerPartId=-1|Location.X=1112|Location.Y=335|Color=8388608|FontID=1|IsHidden=T|Text=710-155124M173200|Name=Mouser Part Number|IsMirrored=T
|RECORD=41|OwnerIndex=340|IndexInSheet=4|OwnerPartId=-1|Location.X=1112|Location.Y=335|Color=8388608|FontID=5|IsHidden=T|Text=https://www.mouser.co.uk/ProductDetail/Wurth-Elektronik/155124M173200?qs=5aG0NVq1C4xPhoUU07x4gQ%3D%3D|Name=Mouser Price/Stock|IsMirrored=T
|RECORD=41|OwnerIndex=340|IndexInSheet=5|OwnerPartId=-1|Location.X=1112|Location.Y=335|Color=8388608|FontID=1|IsHidden=T|Name=Arrow Part Number|IsMirrored=T
|RECORD=41|OwnerIndex=340|IndexInSheet=6|OwnerPartId=-1|Location.X=1112|Location.Y=335|Color=8388608|FontID=1|IsHidden=T|Name=Arrow Price/Stock|IsMirrored=T
|RECORD=14|OwnerIndex=340|IsNotAccesible=T|IndexInSheet=7|OwnerPartId=1|Location.X=1134|Location.Y=295|Corner.X=1194|Corner.Y=335|LineWidth=1|Color=128|AreaColor=11599871|IsSolid=T
|RECORD=2|OwnerIndex=340|OwnerPartId=1|FormalType=1|Electrical=7|PinConglomerate=56|PinLength=20|Location.X=1194|Location.Y=325|Name=ANODE|Designator=1|SwapIDPart=Ž&Ž||PinPropagationDelay=0.000000E+000
|RECORD=2|OwnerIndex=340|OwnerPartId=1|FormalType=1|Electrical=2|PinConglomerate=58|PinLength=20|Location.X=1134|Location.Y=305|Name=B|Designator=2|SwapIDPart=Ž&Ž||PinPropagationDelay=0.000000E+000
|RECORD=2|OwnerIndex=340|OwnerPartId=1|FormalType=1|Electrical=2|PinConglomerate=58|PinLength=20|Location.X=1134|Location.Y=315|Name=G|Designator=3|SwapIDPart=Ž&Ž||PinPropagationDelay=0.000000E+000
|RECORD=2|OwnerIndex=340|OwnerPartId=1|FormalType=1|Electrical=2|PinConglomerate=58|PinLength=20|Location.X=1134|Location.Y=325|Name=R|Designator=4|SwapIDPart=Ž&Ž||PinPropagationDelay=0.000000E+000
|RECORD=34|OwnerIndex=340|IndexInSheet=-1|OwnerPartId=-1|Location.X=1134|Location.Y=335|Color=8388608|FontID=1|Text=D16|Name=Designator|ReadOnlyState=1|IsMirrored=T
|RECORD=41|OwnerIndex=340|IndexInSheet=-1|OwnerPartId=-1|Location.X=1134|Location.Y=285|Color=8388608|FontID=1|Text=155124M173200|Name=Comment|IsMirrored=T
|RECORD=44|OwnerIndex=340
|RECORD=45|OwnerIndex=359|IndexInSheet=-1|ModelName=155124M173200|ModelType=PCBLIB|DatafileCount=1|ModelDatafile0=C:\Users\<user>\Documents\AltiumLL\SamacSys.PcbLib|ModelDatafileEntity0=155124M173200|ModelDatafileKind0=PCBLIB|IsCurrent=T
|RECORD=46|OwnerIndex=360
|RECORD=48|OwnerIndex=360
|RECORD=1|LibReference=155124M173200|ComponentDescription=LED (Multiple)|PartCount=2|DisplayModeCount=1|IndexInSheet=18|OwnerPartId=-1|Location.X=1194|Location.Y=265|IsMirrored=T|CurrentPartId=1|LibraryPath=*|SourceLibraryName=SamacSys.SchLib|TargetFileName=*|AreaColor=11599871|Color=128|PartIDLocked=T|DesignItemId=155124M173200|AllPinCount=4
|RECORD=41|OwnerIndex=363|OwnerPartId=-1|Location.X=1112|Location.Y=265|Color=8388608|FontID=5|IsHidden=T|Text=https://www.mouser.com/ds/2/445/155124M173200-1113601.pdf|Name=Datasheet Link|IsMirrored=T
|RECORD=41|OwnerIndex=363|IndexInSheet=1|OwnerPartId=-1|Location.X=1112|Location.Y=265|Color=8388608|FontID=1|IsHidden=T|Text=Wurth Elektronik|Name=Manufacturer_Name|IsMirrored=T
|RECORD=41|OwnerIndex=363|IndexInSheet=2|OwnerPartId=-1|Location.X=1112|Location.Y=265|Color=8388608|FontID=1|IsHidden=T|Text=155124M173200|Name=Manufacturer_Part_Number|IsMirrored=T
|RECORD=41|OwnerIndex=363|IndexInSheet=3|OwnerPartId=-1|Location.X=1112|Location.Y=265|Color=8388608|FontID=1|IsHidden=T|Text=710-155124M173200|Name=Mouser Part Number|IsMirrored=T
|RECORD=41|OwnerIndex=363|IndexInSheet=4|OwnerPartId=-1|Location.X=1112|Location.Y=265|Color=8388608|FontID=5|IsHidden=T|Text=https://www.mouser.co.uk/ProductDetail/Wurth-Elektronik/155124M173200?qs=5aG0NVq1C4xPhoUU07x4gQ%3D%3D|Name=Mouser Price/Stock|IsMirrored=T
|RECORD=41|OwnerIndex=363|IndexInSheet=5|OwnerPartId=-1|Location.X=1112|Location.Y=265|Color=8388608|FontID=1|IsHidden=T|Name=Arrow Part Number|IsMirrored=T
|RECORD=41|OwnerIndex=363|IndexInSheet=6|OwnerPartId=-1|Location.X=1112|Location.Y=265|Color=8388608|FontID=1|IsHidden=T|Name=Arrow Price/Stock|IsMirrored=T
|RECORD=14|OwnerIndex=363|IsNotAccesible=T|IndexInSheet=7|OwnerPartId=1|Location.X=1134|Location.Y=225|Corner.X=1194|Corner.Y=265|LineWidth=1|Color=128|AreaColor=11599871|IsSolid=T
|RECORD=2|OwnerIndex=363|OwnerPartId=1|FormalType=1|Electrical=7|PinConglomerate=56|PinLength=20|Location.X=1194|Location.Y=255|Name=ANODE|Designator=1|SwapIDPart=Ž&Ž||PinPropagationDelay=0.000000E+000
|RECORD=2|OwnerIndex=363|OwnerPartId=1|FormalType=1|Electrical=2|PinConglomerate=58|PinLength=20|Location.X=1134|Location.Y=235|Name=B|Designator=2|SwapIDPart=Ž&Ž||PinPropagationDelay=0.000000E+000
|RECORD=2|OwnerIndex=363|OwnerPartId=1|FormalType=1|Electrical=2|PinConglomerate=58|PinLength=20|Location.X=1134|Location.Y=245|Name=G|Designator=3|SwapIDPart=Ž&Ž||PinPropagationDelay=0.000000E+000
|RECORD=2|OwnerIndex=363|OwnerPartId=1|FormalType=1|Electrical=2|PinConglomerate=58|PinLength=20|Location.X=1134|Location.Y=255|Name=R|Designator=4|SwapIDPart=Ž&Ž||PinPropagationDelay=0.000000E+000
|RECORD=34|OwnerIndex=363|IndexInSheet=-1|OwnerPartId=-1|Location.X=1134|Location.Y=265|Color=8388608|FontID=1|Text=D17|Name=Designator|ReadOnlyState=1|IsMirrored=T
|RECORD=41|OwnerIndex=363|IndexInSheet=-1|OwnerPartId=-1|Location.X=1134|Location.Y=215|Color=8388608|FontID=1|Text=155124M173200|Name=Comment|IsMirrored=T
|RECORD=44|OwnerIndex=363
|RECORD=45|OwnerIndex=382|IndexInSheet=-1|ModelName=155124M173200|ModelType=PCBLIB|DatafileCount=1|ModelDatafile0=C:\Users\<user>\Documents\AltiumLL\SamacSys.PcbLib|ModelDatafileEntity0=155124M173200|ModelDatafileKind0=PCBLIB|IsCurrent=T
|RECORD=46|OwnerIndex=383
|RECORD=48|OwnerIndex=383
|RECORD=1|LibReference=155124M173200|ComponentDescription=LED (Multiple)|PartCount=2|DisplayModeCount=1|IndexInSheet=19|OwnerPartId=-1|Location.X=1194|Location.Y=195|IsMirrored=T|CurrentPartId=1|LibraryPath=*|SourceLibraryName=SamacSys.SchLib|TargetFileName=*|AreaColor=11599871|Color=128|PartIDLocked=T|DesignItemId=155124M173200|AllPinCount=4
|RECORD=41|OwnerIndex=386|OwnerPartId=-1|Location.X=1112|Location.Y=195|Color=8388608|FontID=5|IsHidden=T|Text=https://www.mouser.com/ds/2/445/155124M173200-1113601.pdf|Name=Datasheet Link|IsMirrored=T
|RECORD=41|OwnerIndex=386|IndexInSheet=1|OwnerPartId=-1|Location.X=1112|Location.Y=195|Color=8388608|FontID=1|IsHidden=T|Text=Wurth Elektronik|Name=Manufacturer_Name|IsMirrored=T
|RECORD=41|OwnerIndex=386|IndexInSheet=2|OwnerPartId=-1|Location.X=1112|Location.Y=195|Color=8388608|FontID=1|IsHidden=T|Text=155124M173200|Name=Manufacturer_Part_Number|IsMirrored=T
|RECORD=41|OwnerIndex=386|IndexInSheet=3|OwnerPartId=-1|Location.X=1112|Location.Y=195|Color=8388608|FontID=1|IsHidden=T|Text=710-155124M173200|Name=Mouser Part Number|IsMirrored=T
|RECORD=41|OwnerIndex=386|IndexInSheet=4|OwnerPartId=-1|Location.X=1112|Location.Y=195|Color=8388608|FontID=5|IsHidden=T|Text=https://www.mouser.co.uk/ProductDetail/Wurth-Elektronik/155124M173200?qs=5aG0NVq1C4xPhoUU07x4gQ%3D%3D|Name=Mouser Price/Stock|IsMirrored=T
|RECORD=41|OwnerIndex=386|IndexInSheet=5|OwnerPartId=-1|Location.X=1112|Location.Y=195|Color=8388608|FontID=1|IsHidden=T|Name=Arrow Part Number|IsMirrored=T
|RECORD=41|OwnerIndex=386|IndexInSheet=6|OwnerPartId=-1|Location.X=1112|Location.Y=195|Color=8388608|FontID=1|IsHidden=T|Name=Arrow Price/Stock|IsMirrored=T
|RECORD=14|OwnerIndex=386|IsNotAccesible=T|IndexInSheet=7|OwnerPartId=1|Location.X=1134|Location.Y=155|Corner.X=1194|Corner.Y=195|LineWidth=1|Color=128|AreaColor=11599871|IsSolid=T
|RECORD=2|OwnerIndex=386|OwnerPartId=1|FormalType=1|Electrical=7|PinConglomerate=56|PinLength=20|Location.X=1194|Location.Y=185|Name=ANODE|Designator=1|SwapIDPart=Ž&Ž||PinPropagationDelay=0.000000E+000
|RECORD=2|OwnerIndex=386|OwnerPartId=1|FormalType=1|Electrical=2|PinConglomerate=58|PinLength=20|Location.X=1134|Location.Y=165|Name=B|Designator=2|SwapIDPart=Ž&Ž||PinPropagationDelay=0.000000E+000
|RECORD=2|OwnerIndex=386|OwnerPartId=1|FormalType=1|Electrical=2|PinConglomerate=58|PinLength=20|Location.X=1134|Location.Y=175|Name=G|Designator=3|SwapIDPart=Ž&Ž||PinPropagationDelay=0.000000E+000
|RECORD=2|OwnerIndex=386|OwnerPartId=1|FormalType=1|Electrical=2|PinConglomerate=58|PinLength=20|Location.X=1134|Location.Y=185|Name=R|Designator=4|SwapIDPart=Ž&Ž||PinPropagationDelay=0.000000E+000
|RECORD=34|OwnerIndex=386|IndexInSheet=-1|OwnerPartId=-1|Location.X=1134|Location.Y=195|Color=8388608|FontID=1|Text=D18|Name=Designator|ReadOnlyState=1|IsMirrored=T
|RECORD=41|OwnerIndex=386|IndexInSheet=-1|OwnerPartId=-1|Location.X=1134|Location.Y=145|Color=8388608|FontID=1|Text=155124M173200|Name=Comment|IsMirrored=T
|RECORD=44|OwnerIndex=386
|RECORD=45|OwnerIndex=405|IndexInSheet=-1|ModelName=155124M173200|ModelType=PCBLIB|DatafileCount=1|ModelDatafile0=C:\Users\<user>\Documents\AltiumLL\SamacSys.PcbLib|ModelDatafileEntity0=155124M173200|ModelDatafileKind0=PCBLIB|IsCurrent=T
|RECORD=46|OwnerIndex=406
|RECORD=48|OwnerIndex=406
|RECORD=1|LibReference=IS32FL3207|PartCount=2|DisplayModeCount=1|IndexInSheet=20|OwnerPartId=-1|Location.X=644|Location.Y=455|CurrentPartId=1|LibraryPath=*|SourceLibraryName=IS32FL3207.SchLib|TargetFileName=*|AreaColor=11599871|Color=128|PartIDLocked=T|PinsMoveable=T|DesignItemId=IS32FL3207|AllPinCount=29
|RECORD=14|OwnerIndex=409|IsNotAccesible=T|OwnerPartId=1|Location.X=674|Location.Y=215|Corner.X=764|Corner.Y=455|Color=128|AreaColor=11599871|IsSolid=T
|RECORD=2|OwnerIndex=409|OwnerPartId=1|FormalType=1|PinConglomerate=26|PinLength=30|Location.X=674|Location.Y=385|Name=SDB|Designator=1|SwapIDPart=Ž&Ž||PinPropagationDelay=0.000000E+000
|RECORD=2|OwnerIndex=409|OwnerPartId=1|FormalType=1|PinConglomerate=26|PinLength=30|Location.X=674|Location.Y=415|Name=AD|Designator=2|SwapIDPart=Ž&Ž||PinPropagationDelay=0.000000E+000
|RECORD=2|OwnerIndex=409|OwnerPartId=1|FormalType=1|PinConglomerate=26|PinLength=30|Location.X=674|Location.Y=295|Name=VCC|Designator=3|SwapIDPart=Ž&Ž||PinPropagationDelay=0.000000E+000
|RECORD=2|OwnerIndex=409|OwnerPartId=1|FormalType=1|PinConglomerate=26|PinLength=30|Location.X=674|Location.Y=265|Name=GND|Designator=4|SwapIDPart=Ž&Ž||PinPropagationDelay=0.000000E+000
|RECORD=2|OwnerIndex=409|OwnerPartId=1|FormalType=1|PinConglomerate=26|PinLength=30|Location.X=674|Location.Y=365|Name=ISET|Designator=5|SwapIDPart=Ž&Ž||PinPropagationDelay=0.000000E+000
|RECORD=2|OwnerIndex=409|OwnerPartId=1|FormalType=1|PinConglomerate=26|PinLength=30|Location.X=674|Location.Y=445|Name=SDA|Designator=6|SwapIDPart=Ž&Ž||PinPropagationDelay=0.000000E+000
|RECORD=2|OwnerIndex=409|OwnerPartId=1|FormalType=1|PinConglomerate=26|PinLength=30|Location.X=674|Location.Y=435|Name=SCL|Designator=7|SwapIDPart=Ž&Ž||PinPropagationDelay=0.000000E+000
|RECORD=2|OwnerIndex=409|OwnerPartId=1|FormalType=1|PinConglomerate=24|PinLength=30|Location.X=764|Location.Y=445|Name=OUT1|Designator=8|SwapIDPart=Ž&Ž||PinPropagationDelay=0.000000E+000
|RECORD=2|OwnerIndex=409|OwnerPartId=1|FormalType=1|PinConglomerate=24|PinLength=30|Location.X=764|Location.Y=435|Name=OUT2|Designator=9|SwapIDPart=Ž&Ž||PinPropagationDelay=0.000000E+000
|RECORD=2|OwnerIndex=409|OwnerPartId=1|FormalType=1|PinConglomerate=24|PinLength=30|Location.X=764|Location.Y=425|Name=OUT3|Designator=10|SwapIDPart=Ž&Ž||PinPropagationDelay=0.000000E+000
|RECORD=2|OwnerIndex=409|OwnerPartId=1|FormalType=1|PinConglomerate=26|PinLength=30|Location.X=674|Location.Y=255|Name=GND|Designator=11|SwapIDPart=Ž&Ž||PinPropagationDelay=0.000000E+000
|RECORD=2|OwnerIndex=409|OwnerPartId=1|FormalType=1|PinConglomerate=24|PinLength=30|Location.X=764|Location.Y=405|Name=OUT4|Designator=12|SwapIDPart=Ž&Ž||PinPropagationDelay=0.000000E+000
|RECORD=2|OwnerIndex=409|OwnerPartId=1|FormalType=1|PinConglomerate=24|PinLength=30|Location.X=764|Location.Y=395|Name=OUT5|Designator=13|SwapIDPart=Ž&Ž||PinPropagationDelay=0.000000E+000
|RECORD=2|OwnerIndex=409|OwnerPartId=1|FormalType=1|PinConglomerate=24|PinLength=30|Location.X=764|Location.Y=385|Name=OUT6|Designator=14|SwapIDPart=Ž&Ž||PinPropagationDelay=0.000000E+000
|RECORD=2|OwnerIndex=409|OwnerPartId=1|FormalType=1|PinConglomerate=24|PinLength=30|Location.X=764|Location.Y=365|Name=OUT7|Designator=15|SwapIDPart=Ž&Ž||PinPropagationDelay=0.000000E+000
|RECORD=2|OwnerIndex=409|OwnerPartId=1|FormalType=1|PinConglomerate=24|PinLength=30|Location.X=764|Location.Y=355|Name=OUT8|Designator=16|SwapIDPart=Ž&Ž||PinPropagationDelay=0.000000E+000
|RECORD=2|OwnerIndex=409|OwnerPartId=1|FormalType=1|PinConglomerate=24|PinLength=30|Location.X=764|Location.Y=345|Name=OUT9|Designator=17|SwapIDPart=Ž&Ž||PinPropagationDelay=0.000000E+000
|RECORD=2|OwnerIndex=409|OwnerPartId=1|FormalType=1|PinConglomerate=26|PinLength=30|Location.X=674|Location.Y=245|Name=GND|Designator=18|SwapIDPart=Ž&Ž||PinPropagationDelay=0.000000E+000
|RECORD=2|OwnerIndex=409|OwnerPartId=1|FormalType=1|PinConglomerate=24|PinLength=30|Location.X=764|Location.Y=325|Name=OUT10|Designator=19|SwapIDPart=Ž&Ž||PinPropagationDelay=0.000000E+000
|RECORD=2|OwnerIndex=409|OwnerPartId=1|FormalType=1|PinConglomerate=24|PinLength=30|Location.X=764|Location.Y=315|Name=OUT11|Designator=20|SwapIDPart=Ž&Ž||PinPropagationDelay=0.000000E+000
|RECORD=2|OwnerIndex=409|OwnerPartId=1|FormalType=1|PinConglomerate=24|PinLength=30|Location.X=764|Location.Y=305|Name=OUT12|Designator=21|SwapIDPart=Ž&Ž||PinPropagationDelay=0.000000E+000
|RECORD=2|OwnerIndex=409|OwnerPartId=1|FormalType=1|PinConglomerate=24|PinLength=30|Location.X=764|Location.Y=285|Name=OUT13|Designator=22|SwapIDPart=Ž&Ž||PinPropagationDelay=0.000000E+000
|RECORD=2|OwnerIndex=409|OwnerPartId=1|FormalType=1|PinConglomerate=24|PinLength=30|Location.X=764|Location.Y=275|Name=OUT14|Designator=23|SwapIDPart=Ž&Ž||PinPropagationDelay=0.000000E+000
|RECORD=2|OwnerIndex=409|OwnerPartId=1|FormalType=1|PinConglomerate=24|PinLength=30|Location.X=764|Location.Y=265|Name=OUT15|Designator=24|SwapIDPart=Ž&Ž||PinPropagationDelay=0.000000E+000
|RECORD=2|OwnerIndex=409|OwnerPartId=1|FormalType=1|PinConglomerate=26|PinLength=30|Location.X=674|Location.Y=235|Name=GND|Designator=25|SwapIDPart=Ž&Ž||PinPropagationDelay=0.000000E+000
|RECORD=2|OwnerIndex=409|OwnerPartId=1|FormalType=1|PinConglomerate=24|PinLength=30|Location.X=764|Location.Y=245|Name=OUT16|Designator=26|SwapIDPart=Ž&Ž||PinPropagationDelay=0.000000E+000
|RECORD=2|OwnerIndex=409|OwnerPartId=1|FormalType=1|PinConglomerate=24|PinLength=30|Location.X=764|Location.Y=235|Name=OUT17|Designator=27|SwapIDPart=Ž&Ž||PinPropagationDelay=0.000000E+000
|RECORD=2|OwnerIndex=409|OwnerPartId=1|FormalType=1|PinConglomerate=24|PinLength=30|Location.X=764|Location.Y=225|Name=OUT18|Designator=28|SwapIDPart=Ž&Ž||PinPropagationDelay=0.000000E+000
|RECORD=2|OwnerIndex=409|OwnerPartId=1|FormalType=1|PinConglomerate=26|PinLength=30|Location.X=674|Location.Y=225|Name=EP|Designator=29|SwapIDPart=Ž&Ž||PinPropagationDelay=0.000000E+000
|RECORD=34|OwnerIndex=409|IndexInSheet=-1|OwnerPartId=-1|Location.X=674|Location.Y=455|Color=8388608|FontID=1|Text=U6|Name=Designator|ReadOnlyState=1
|RECORD=41|OwnerIndex=409|IndexInSheet=-1|OwnerPartId=-1|Location.X=674|Location.Y=205|Color=8388608|FontID=1|Text=IS32FL3207|Name=Comment
|RECORD=44|OwnerIndex=409
|RECORD=45|OwnerIndex=471|IndexInSheet=-1|ModelName=IS32FL3207|ModelType=PCBLIB|DatafileCount=1|ModelDatafileEntity0=IS32FL3207|ModelDatafileKind0=PCBLib|IsCurrent=T
|RECORD=46|OwnerIndex=472
|RECORD=48|OwnerIndex=472
|RECORD=17|IndexInSheet=21|OwnerPartId=-1|ShowNetName=T|Location.X=1244|Location.Y=555|Orientation=1|Color=128|FontID=1|Text=+3.3V
|RECORD=4|IndexInSheet=22|OwnerPartId=-1|Location.X=734|Location.Y=575|Color=8388608|FontID=6|Text=IO STATUS LEDS
|RECORD=4|IndexInSheet=23|OwnerPartId=-1|Location.X=1264|Location.Y=485|Color=8388608|FontID=6|Text=GNSS 1
|RECORD=4|IndexInSheet=24|OwnerPartId=-1|Location.X=1264|Location.Y=425|Color=8388608|FontID=6|Text=GNSS 2
|RECORD=4|IndexInSheet=25|OwnerPartId=-1|Location.X=1264|Location.Y=365|Color=8388608|FontID=6|Text=IO 1
|RECORD=4|IndexInSheet=26|OwnerPartId=-1|Location.X=1264|Location.Y=305|Color=8388608|FontID=6|Text=IO 2
|RECORD=4|IndexInSheet=27|OwnerPartId=-1|Location.X=1264|Location.Y=235|Color=8388608|FontID=6|Text=IO 3
|RECORD=4|IndexInSheet=28|OwnerPartId=-1|Location.X=1264|Location.Y=165|Color=8388608|FontID=6|Text=IO 4
|RECORD=1|LibReference=CAP|ComponentDescription=C0603X104K5RACAUTO|PartCount=2|DisplayModeCount=2|IndexInSheet=29|OwnerPartId=-1|Location.X=524|Location.Y=185|Orientation=1|CurrentPartId=1|SourceLibraryName=Altium Content Vault|TargetFileName=*|AreaColor=11599871|Color=128|PartIDLocked=F|DesignItemId=CMP-2006-00003-1|AllPinCount=2
|RECORD=2|OwnerIndex=483|OwnerPartId=1|OwnerPartDisplayMode=1|FormalType=1|Electrical=4|PinConglomerate=35|PinLength=10|Location.X=534|Location.Y=185|Name=1|Designator=1|PinPropagationDelay=0.000000E+000
|RECORD=2|OwnerIndex=483|OwnerPartId=1|OwnerPartDisplayMode=1|FormalType=1|Electrical=4|PinConglomerate=33|PinLength=10|Location.X=534|Location.Y=195|Name=2|Designator=2|PinPropagationDelay=0.000000E+000
|RECORD=13|OwnerIndex=483|IsNotAccesible=T|IndexInSheet=2|OwnerPartId=1|OwnerPartDisplayMode=1|Location.X=542|Location.Y=185|Corner.X=526|Corner.Y=185|LineWidth=1|Color=16711680
|RECORD=13|OwnerIndex=483|IsNotAccesible=T|IndexInSheet=3|OwnerPartId=1|OwnerPartDisplayMode=1|Location.X=534|Location.Y=189|Corner.X=534|Corner.Y=195|LineWidth=1|Color=16711680
|RECORD=12|OwnerIndex=483|IsNotAccesible=T|IndexInSheet=4|OwnerPartId=1|OwnerPartDisplayMode=1|Location.X=534|Location.Y=205|Radius=16|LineWidth=1|StartAngle=241.000|EndAngle=270.000|Color=16711680
|RECORD=12|OwnerIndex=483|IsNotAccesible=T|IndexInSheet=5|OwnerPartId=1|OwnerPartDisplayMode=1|Location.X=534|Location.Y=205|Radius=16|LineWidth=1|StartAngle=270.000|EndAngle=299.000|Color=16711680
|RECORD=2|OwnerIndex=483|OwnerPartId=1|FormalType=1|Electrical=4|PinConglomerate=35|PinLength=10|Location.X=534|Location.Y=185|Name=1|Designator=1|PinPropagationDelay=0.000000E+000
|RECORD=2|OwnerIndex=483|OwnerPartId=1|FormalType=1|Electrical=4|PinConglomerate=33|PinLength=10|Location.X=534|Location.Y=195|Name=2|Designator=2|PinPropagationDelay=0.000000E+000
|RECORD=13|OwnerIndex=483|IsNotAccesible=T|IndexInSheet=8|OwnerPartId=1|Location.X=526|Location.Y=192|Corner.X=542|Corner.Y=192|LineWidth=1|Color=16711680
|RECORD=13|OwnerIndex=483|IsNotAccesible=T|IndexInSheet=9|OwnerPartId=1|Location.X=542|Location.Y=188|Corner.X=526|Corner.Y=188|LineWidth=1|Color=16711680
|RECORD=6|OwnerIndex=483|IsNotAccesible=T|IndexInSheet=10|OwnerPartId=1|LineWidth=1|Color=16711680|LocationCount=2|X1=534|Y1=185|X2=534|Y2=188
|RECORD=6|OwnerIndex=483|IsNotAccesible=T|IndexInSheet=11|OwnerPartId=1|LineWidth=1|Color=16711680|LocationCount=2|X1=534|Y1=195|X2=534|Y2=192
|RECORD=41|OwnerIndex=483|IndexInSheet=12|OwnerPartId=-1|Location.X=525|Location.Y=207|Color=8388608|FontID=1|IsHidden=T|Text=Kemet|Name=Manufacturer
|RECORD=41|OwnerIndex=483|IndexInSheet=13|OwnerPartId=-1|Location.X=525|Location.Y=207|Color=8388608|FontID=1|IsHidden=T|Text=C0603X104K5RACAUTO|Name=Part Number
|RECORD=34|OwnerIndex=483|IndexInSheet=-1|OwnerPartId=-1|Location.X=543|Location.Y=186|Color=8388608|FontID=1|Text=C40|Name=Designator|ReadOnlyState=1
|RECORD=41|OwnerIndex=483|IndexInSheet=-1|OwnerPartId=-1|Location.X=543|Location.Y=176|Color=8388608|FontID=1|Text=0.1uF|Name=Comment
|RECORD=44|OwnerIndex=483
|RECORD=45|OwnerIndex=504|IndexInSheet=-1|Description=Chip Capacitor, 2-Leads, Body 1.60x0.80mm, IPC Low Density|UseComponentLibrary=T|ModelName=CAPC1608X87X45ML20T05|ModelType=PCBLIB|DatafileCount=1|ModelDatafileEntity0=CAPC1608X87X45ML20T05|ModelDatafileKind0=PCBLib|IsCurrent=T|DatalinksLocked=T|DatabaseDatalinksLocked=T
|RECORD=46|OwnerIndex=505
|RECORD=48|OwnerIndex=505
|RECORD=41|OwnerIndex=507|IndexInSheet=-1|OwnerPartId=-1|Color=8388608|FontID=1|Text=2D|Name=Available Preview Images
|RECORD=45|OwnerIndex=504|IndexInSheet=-1|Description=Chip Capacitor, 2-Leads, Body 1.60x0.80mm, IPC High Density|UseComponentLibrary=T|ModelName=CAPC1608X87X45LL20T05|ModelType=PCBLIB|DatafileCount=1|ModelDatafileEntity0=CAPC1608X87X45LL20T05|ModelDatafileKind0=PCBLib|DatalinksLocked=T|DatabaseDatalinksLocked=T
|RECORD=46|OwnerIndex=509
|RECORD=48|OwnerIndex=509
|RECORD=41|OwnerIndex=511|IndexInSheet=-1|OwnerPartId=-1|Color=8388608|FontID=1|Text=2D|Name=Available Preview Images
|RECORD=45|OwnerIndex=504|IndexInSheet=-1|Description=Chip Capacitor, 2-Leads, Body 1.60x0.80mm, IPC Medium Density|UseComponentLibrary=T|ModelName=CAPC1608X87X45NL20T05|ModelType=PCBLIB|DatafileCount=1|ModelDatafileEntity0=CAPC1608X87X45NL20T05|ModelDatafileKind0=PCBLib|DatalinksLocked=T|DatabaseDatalinksLocked=T
|RECORD=46|OwnerIndex=513
|RECORD=48|OwnerIndex=513
|RECORD=41|OwnerIndex=515|IndexInSheet=-1|OwnerPartId=-1|Color=8388608|FontID=1|Text=2D|Name=Available Preview Images
|RECORD=1|LibReference=e9c51b7dd13d4faca003ae77663ab08|ComponentDescription=CAP CER 1UF 25V X5R 0603|PartCount=2|DisplayModeCount=1|IndexInSheet=30|OwnerPartId=-1|Location.X=444|Location.Y=205|CurrentPartId=1|LibraryPath=*|SourceLibraryName=Altium Content Vault|TargetFileName=*|AreaColor=11599871|Color=128|PartIDLocked=T|DesignItemId=CMP-2006-02216-3|AllPinCount=2
|RECORD=2|OwnerIndex=517|OwnerPartId=1|Electrical=4|PinConglomerate=33|PinLength=7|Location.X=444|Location.Y=198|Name=1|Designator=1|PinName_PositionConglomerate=16|Name_CustomFontID=1|PinDesignator_PositionConglomerate=16|Designator_CustomFontID=1|PinPropagationDelay=0.000000E+000
|RECORD=2|OwnerIndex=517|OwnerPartId=1|Electrical=4|PinConglomerate=35|PinLength=6|Location.X=444|Location.Y=191|Name=2|Designator=2|PinName_PositionConglomerate=16|Name_CustomFontID=1|PinDesignator_PositionConglomerate=16|Designator_CustomFontID=1|PinPropagationDelay=0.000000E+000
|RECORD=13|OwnerIndex=517|IsNotAccesible=T|IndexInSheet=2|OwnerPartId=1|Location.X=454|Location.Y=198|Corner.X=434|Corner.Y=198|LineWidth=1|Color=16711680
|RECORD=13|OwnerIndex=517|IsNotAccesible=T|IndexInSheet=3|OwnerPartId=1|Location.X=454|Location.Y=192|Corner.X=434|Corner.Y=192|LineWidth=1|Color=16711680
|RECORD=13|OwnerIndex=517|IsNotAccesible=T|IndexInSheet=4|OwnerPartId=1|Location.X=444|Location.Y=198|Corner.X=444|Corner.Y=201|LineWidth=1|Color=16711680
|RECORD=13|OwnerIndex=517|IsNotAccesible=T|IndexInSheet=5|OwnerPartId=1|Location.X=444|Location.Y=191|Corner.X=444|Corner.Y=190|LineWidth=1|Color=16711680
|RECORD=41|OwnerIndex=517|IndexInSheet=6|OwnerPartId=-1|Location.X=433|Location.Y=207|Color=8388608|FontID=1|IsHidden=T|Text=Tin|Name=Contact Plating
|RECORD=41|OwnerIndex=517|IndexInSheet=7|OwnerPartId=-1|Location.X=433|Location.Y=207|Color=8388608|FontID=1|IsHidden=T|Text=2|Name=Number of Pins
|RECORD=41|OwnerIndex=517|IndexInSheet=8|OwnerPartId=-1|Location.X=433|Location.Y=207|Color=8388608|FontID=1|IsHidden=T|Text=Lead Free|Name=Lead Free
|RECORD=41|OwnerIndex=517|IndexInSheet=9|OwnerPartId=-1|Location.X=433|Location.Y=207|Color=8388608|FontID=1|IsHidden=T|Text=0.8mm|Name=Depth
|RECORD=41|OwnerIndex=517|IndexInSheet=10|OwnerPartId=-1|Location.X=433|Location.Y=207|Color=8388608|FontID=1|IsHidden=T|Text=1.6mm|Name=Length
|RECORD=41|OwnerIndex=517|IndexInSheet=11|OwnerPartId=-1|Location.X=433|Location.Y=207|Color=8388608|FontID=1|IsHidden=T|Text=Surface Mount|Name=Mount
|RECORD=41|OwnerIndex=517|IndexInSheet=12|OwnerPartId=-1|Location.X=433|Location.Y=207|Color=8388608|FontID=1|IsHidden=T|Text=1608|Name=Case Code (Metric)
|RECORD=41|OwnerIndex=517|IndexInSheet=13|OwnerPartId=-1|Location.X=433|Location.Y=207|Color=8388608|FontID=1|IsHidden=T|Text=85°C|Name=Max Operating Temperature
|RECORD=41|OwnerIndex=517|IndexInSheet=14|OwnerPartId=-1|Location.X=433|Location.Y=207|Color=8388608|FontID=1|IsHidden=T|Text=25V|Name=Voltage
|RECORD=41|OwnerIndex=517|IndexInSheet=15|OwnerPartId=-1|Location.X=433|Location.Y=207|Color=8388608|FontID=1|IsHidden=T|Text=25V|Name=Voltage Rating (DC)
|RECORD=41|OwnerIndex=517|IndexInSheet=16|OwnerPartId=-1|Location.X=433|Location.Y=207|Color=8388608|FontID=1|IsHidden=T|Text=Ceramic|Name=Dielectric Material
|RECORD=41|OwnerIndex=517|IndexInSheet=17|OwnerPartId=-1|Location.X=433|Location.Y=207|Color=8388608|FontID=1|IsHidden=T|Text=No SVHC|Name=REACH SVHC
|RECORD=41|OwnerIndex=517|IndexInSheet=18|OwnerPartId=-1|Location.X=433|Location.Y=207|Color=8388608|FontID=1|IsHidden=T|Text=0.8mm|Name=Height
|RECORD=41|OwnerIndex=517|IndexInSheet=19|OwnerPartId=-1|Location.X=433|Location.Y=207|Color=8388608|FontID=1|IsHidden=T|Text=C0603C|Name=Series
|RECORD=41|OwnerIndex=517|IndexInSheet=20|OwnerPartId=-1|Location.X=433|Location.Y=207|Color=8388608|FontID=1|IsHidden=T|Text=0603|Name=Case/Package
|RECORD=41|OwnerIndex=517|IndexInSheet=21|OwnerPartId=-1|Location.X=433|Location.Y=207|Color=8388608|FontID=1|IsHidden=T|Text=0603|Name=Case Code (Imperial)
|RECORD=41|OwnerIndex=517|IndexInSheet=22|OwnerPartId=-1|Location.X=433|Location.Y=207|Color=8388608|FontID=1|IsHidden=T|Text=1uF|Name=Capacitance
|RECORD=41|OwnerIndex=517|IndexInSheet=23|OwnerPartId=-1|Location.X=433|Location.Y=207|Color=8388608|FontID=1|IsHidden=T|Text=Yes|Name=RoHS Compliant
|RECORD=41|OwnerIndex=517|IndexInSheet=24|OwnerPartId=-1|Location.X=433|Location.Y=207|Color=8388608|FontID=1|IsHidden=T|Text=X5R|Name=Dielectric
|RECORD=41|OwnerIndex=517|IndexInSheet=25|OwnerPartId=-1|Location.X=433|Location.Y=207|Color=8388608|FontID=1|IsHidden=T|Text=Tape and Reel|Name=Packaging
|RECORD=41|OwnerIndex=517|IndexInSheet=26|OwnerPartId=-1|Location.X=433|Location.Y=207|Color=8388608|FontID=1|IsHidden=T|Text=Flat|Name=Construction
|RECORD=41|OwnerIndex=517|IndexInSheet=27|OwnerPartId=-1|Location.X=433|Location.Y=207|Color=8388608|FontID=1|IsHidden=T|Text=0.034inch|Name=Thickness
|RECORD=41|OwnerIndex=517|IndexInSheet=28|OwnerPartId=-1|Location.X=433|Location.Y=207|Color=8388608|FontID=1|IsHidden=T|Text=25V|Name=Voltage Rating
|RECORD=41|OwnerIndex=517|IndexInSheet=29|OwnerPartId=-1|Location.X=433|Location.Y=207|Color=8388608|FontID=1|IsHidden=T|Text=No|Name=Radiation Hardening
|RECORD=41|OwnerIndex=517|IndexInSheet=30|OwnerPartId=-1|Location.X=433|Location.Y=207|Color=8388608|FontID=1|IsHidden=T|Text=0.031inch|Name=Width
|RECORD=41|OwnerIndex=517|IndexInSheet=31|OwnerPartId=-1|Location.X=433|Location.Y=207|Color=8388608|FontID=1|IsHidden=T|Text=-55°C|Name=Min Operating Temperature
|RECORD=41|OwnerIndex=517|IndexInSheet=32|OwnerPartId=-1|Location.X=433|Location.Y=207|Color=8388608|FontID=1|IsHidden=T|Text=SMD/SMT|Name=Termination
|RECORD=41|OwnerIndex=517|IndexInSheet=33|OwnerPartId=-1|Location.X=433|Location.Y=207|Color=8388608|FontID=1|IsHidden=T|Text=10%|Name=Tolerance
|RECORD=41|OwnerIndex=517|IndexInSheet=34|OwnerPartId=-1|Location.X=433|Location.Y=207|Color=8388608|FontID=1|IsHidden=T|Text=4000|Name=Package Quantity
|RECORD=34|OwnerIndex=517|IndexInSheet=-1|OwnerPartId=-1|Location.X=455|Location.Y=192|Color=8388608|FontID=1|Text=C38|Name=Designator|ReadOnlyState=1
|RECORD=41|OwnerIndex=517|IndexInSheet=-1|OwnerPartId=1|Location.X=455|Location.Y=182|Color=8388608|FontID=1|Text=1uF|Name=Comment
|RECORD=44|OwnerIndex=517
|RECORD=45|OwnerIndex=557|IndexInSheet=-1|UseComponentLibrary=T|ModelName=FP-C0603C105K3PACTU-MFG|ModelType=PCBLIB|DatafileCount=1|ModelDatafileEntity0=FP-C0603C105K3PACTU-MFG|ModelDatafileKind0=PCBLib|IsCurrent=T|DatalinksLocked=T|DatabaseDatalinksLocked=T
|RECORD=46|OwnerIndex=558
|RECORD=48|OwnerIndex=558
|RECORD=45|OwnerIndex=557|IndexInSheet=-1|UseComponentLibrary=T|ModelName=FP-C0603C105K3PACTU-IPC_C|ModelType=PCBLIB|DatafileCount=1|ModelDatafileEntity0=FP-C0603C105K3PACTU-IPC_C|ModelDatafileKind0=PCBLib|DatalinksLocked=T|DatabaseDatalinksLocked=T
|RECORD=46|OwnerIndex=561
|RECORD=48|OwnerIndex=561
|RECORD=45|OwnerIndex=557|IndexInSheet=-1|UseComponentLibrary=T|ModelName=FP-C0603C105K3PACTU-IPC_B|ModelType=PCBLIB|DatafileCount=1|ModelDatafileEntity0=FP-C0603C105K3PACTU-IPC_B|ModelDatafileKind0=PCBLib|DatalinksLocked=T|DatabaseDatalinksLocked=T
|RECORD=46|OwnerIndex=564
|RECORD=48|OwnerIndex=564
|RECORD=45|OwnerIndex=557|IndexInSheet=-1|UseComponentLibrary=T|ModelName=FP-C0603C105K3PACTU-IPC_A|ModelType=PCBLIB|DatafileCount=1|ModelDatafileEntity0=FP-C0603C105K3PACTU-IPC_A|ModelDatafileKind0=PCBLib|DatalinksLocked=T|DatabaseDatalinksLocked=T
|RECORD=46|OwnerIndex=567
|RECORD=48|OwnerIndex=567
|RECORD=1|LibReference=1029c3af85768c4190bb7ad29bc67b5|ComponentDescription=RES SMD 100K OHM 1% 1/10W 0603|PartCount=2|DisplayModeCount=1|IndexInSheet=31|OwnerPartId=-1|Location.X=364|Location.Y=165|Orientation=1|CurrentPartId=1|LibraryPath=*|SourceLibraryName=Altium Content Vault|TargetFileName=*|AreaColor=11599871|Color=128|PartIDLocked=T|DesignItemId=CMP-2100-03662-2|AllPinCount=2|ComponentKindVersion2=5
|RECORD=2|OwnerIndex=570|OwnerPartId=1|Electrical=4|PinConglomerate=35|PinLength=20|Location.X=364|Location.Y=185|Name=1|Designator=1|PinPropagationDelay=0.000000E+000
|RECORD=2|OwnerIndex=570|OwnerPartId=1|Electrical=4|PinConglomerate=33|PinLength=20|Location.X=364|Location.Y=215|Name=2|Designator=2|PinPropagationDelay=0.000000E+000
|RECORD=13|OwnerIndex=570|IsNotAccesible=T|IndexInSheet=2|OwnerPartId=1|Location.X=364|Location.Y=185|Corner.X=359|Corner.Y=188|LineWidth=1|Color=16711680
|RECORD=13|OwnerIndex=570|IsNotAccesible=T|IndexInSheet=3|OwnerPartId=1|Location.X=359|Location.Y=188|Corner.X=369|Corner.Y=193|LineWidth=1|Color=16711680
|RECORD=13|OwnerIndex=570|IsNotAccesible=T|IndexInSheet=4|OwnerPartId=1|Location.X=369|Location.Y=193|Corner.X=359|Corner.Y=198|LineWidth=1|Color=16711680
|RECORD=13|OwnerIndex=570|IsNotAccesible=T|IndexInSheet=5|OwnerPartId=1|Location.X=359|Location.Y=198|Corner.X=369|Corner.Y=203|LineWidth=1|Color=16711680
|RECORD=13|OwnerIndex=570|IsNotAccesible=T|IndexInSheet=6|OwnerPartId=1|Location.X=369|Location.Y=203|Corner.X=359|Corner.Y=208|LineWidth=1|Color=16711680
|RECORD=13|OwnerIndex=570|IsNotAccesible=T|IndexInSheet=7|OwnerPartId=1|Location.X=359|Location.Y=208|Corner.X=369|Corner.Y=213|LineWidth=1|Color=16711680
|RECORD=13|OwnerIndex=570|IsNotAccesible=T|IndexInSheet=8|OwnerPartId=1|Location.X=369|Location.Y=213|Corner.X=364|Corner.Y=215|LineWidth=1|Color=16711680
|RECORD=13|OwnerIndex=570|IsNotAccesible=T|IndexInSheet=9|OwnerPartId=1|Location.X=364|Location.Y=185|Corner.X=364|Corner.Y=182|LineWidth=1|Color=16711680
|RECORD=13|OwnerIndex=570|IsNotAccesible=T|IndexInSheet=10|OwnerPartId=1|Location.X=364|Location.Y=215|Corner.X=364|Corner.Y=218|LineWidth=1|Color=16711680
|RECORD=41|OwnerIndex=570|IndexInSheet=11|OwnerPartId=-1|Location.X=358|Location.Y=237|Color=8388608|FontID=1|IsHidden=T|Text=1.6mm|Name=Length
|RECORD=41|OwnerIndex=570|IndexInSheet=12|OwnerPartId=-1|Location.X=358|Location.Y=237|Color=8388608|FontID=1|IsHidden=T|Text=Lead Free|Name=Lead Free
|RECORD=41|OwnerIndex=570|IndexInSheet=13|OwnerPartId=-1|Location.X=358|Location.Y=237|Color=8388608|FontID=1|IsHidden=T|Text=2|Name=Number of Terminations
|RECORD=41|OwnerIndex=570|IndexInSheet=14|OwnerPartId=-1|Location.X=358|Location.Y=237|Color=8388608|FontID=1|IsHidden=T|Text=50V|Name=Voltage Rating (DC)
|RECORD=41|OwnerIndex=570|IndexInSheet=15|OwnerPartId=-1|Location.X=358|Location.Y=237|Color=8388608|FontID=1|IsHidden=T|Text=Tape and Reel|Name=Packaging
|RECORD=41|OwnerIndex=570|IndexInSheet=16|OwnerPartId=-1|Location.X=358|Location.Y=237|Color=8388608|FontID=1|IsHidden=T|Text=50V|Name=Voltage Rating
|RECORD=41|OwnerIndex=570|IndexInSheet=17|OwnerPartId=-1|Location.X=358|Location.Y=237|Color=8388608|FontID=1|IsHidden=T|Text=SMD/SMT|Name=Termination
|RECORD=41|OwnerIndex=570|IndexInSheet=18|OwnerPartId=-1|Location.X=358|Location.Y=237|Color=8388608|FontID=1|IsHidden=T|Text=0.8mm|Name=Width
|RECORD=41|OwnerIndex=570|IndexInSheet=19|OwnerPartId=-1|Location.X=358|Location.Y=237|Color=8388608|FontID=1|IsHidden=T|Text=100kR|Name=Resistance
|RECORD=41|OwnerIndex=570|IndexInSheet=20|OwnerPartId=-1|Location.X=358|Location.Y=237|Color=8388608|FontID=1|IsHidden=T|Text=Thick Film|Name=Resistor Type
|RECORD=41|OwnerIndex=570|IndexInSheet=21|OwnerPartId=-1|Location.X=358|Location.Y=237|Color=8388608|FontID=1|IsHidden=T|Text=100mW|Name=Max Power Dissipation
|RECORD=41|OwnerIndex=570|IndexInSheet=22|OwnerPartId=-1|Location.X=358|Location.Y=237|Color=8388608|FontID=1|IsHidden=T|Text=1%|Name=Resistance Tolerance
|RECORD=41|OwnerIndex=570|IndexInSheet=23|OwnerPartId=-1|Location.X=358|Location.Y=237|Color=8388608|FontID=1|IsHidden=T|Text=Moisture Resistant|Name=Features
|RECORD=41|OwnerIndex=570|IndexInSheet=24|OwnerPartId=-1|Location.X=358|Location.Y=237|Color=8388608|FontID=1|IsHidden=T|Text=0.45mm|Name=Height
|RECORD=41|OwnerIndex=570|IndexInSheet=25|OwnerPartId=-1|Location.X=358|Location.Y=237|Color=8388608|FontID=1|IsHidden=T|Text=Rectangular|Name=Construction
|RECORD=41|OwnerIndex=570|IndexInSheet=26|OwnerPartId=-1|Location.X=358|Location.Y=237|Color=8388608|FontID=1|IsHidden=T|Text=0603|Name=Case/Package
|RECORD=41|OwnerIndex=570|IndexInSheet=27|OwnerPartId=-1|Location.X=358|Location.Y=237|Color=8388608|FontID=1|IsHidden=T|Text=Not|Name=Military Standard
|RECORD=41|OwnerIndex=570|IndexInSheet=28|OwnerPartId=-1|Location.X=358|Location.Y=237|Color=8388608|FontID=1|IsHidden=T|Text=0603|Name=Case Code (Imperial)
|RECORD=41|OwnerIndex=570|IndexInSheet=29|OwnerPartId=-1|Location.X=358|Location.Y=237|Color=8388608|FontID=1|IsHidden=T|Text=100ppm/°C|Name=Temperature Coefficient
|RECORD=41|OwnerIndex=570|IndexInSheet=30|OwnerPartId=-1|Location.X=358|Location.Y=237|Color=8388608|FontID=1|IsHidden=T|Text=RC|Name=Series
|RECORD=41|OwnerIndex=570|IndexInSheet=31|OwnerPartId=-1|Location.X=358|Location.Y=237|Color=8388608|FontID=1|IsHidden=T|Text=THICK FILM|Name=Technology
|RECORD=41|OwnerIndex=570|IndexInSheet=32|OwnerPartId=-1|Location.X=358|Location.Y=237|Color=8388608|FontID=1|IsHidden=T|Text=0.8mm|Name=Depth
|RECORD=41|OwnerIndex=570|IndexInSheet=33|OwnerPartId=-1|Location.X=358|Location.Y=237|Color=8388608|FontID=1|IsHidden=T|Text=Yes|Name=RoHS Compliant
|RECORD=41|OwnerIndex=570|IndexInSheet=34|OwnerPartId=-1|Location.X=358|Location.Y=237|Color=8388608|FontID=1|IsHidden=T|Text=75V|Name=Working Voltage
|RECORD=41|OwnerIndex=570|IndexInSheet=35|OwnerPartId=-1|Location.X=358|Location.Y=237|Color=8388608|FontID=1|IsHidden=T|Text=No SVHC|Name=REACH SVHC
|RECORD=41|OwnerIndex=570|IndexInSheet=36|OwnerPartId=-1|Location.X=358|Location.Y=237|Color=8388608|FontID=1|IsHidden=T|Text=-55°C|Name=Min Operating Temperature
|RECORD=41|OwnerIndex=570|IndexInSheet=37|OwnerPartId=-1|Location.X=358|Location.Y=237|Color=8388608|FontID=1|IsHidden=T|Text=1608|Name=Case Code (Metric)
|RECORD=41|OwnerIndex=570|IndexInSheet=38|OwnerPartId=-1|Location.X=358|Location.Y=237|Color=8388608|FontID=1|IsHidden=T|Text=155°C|Name=Max Operating Temperature
|RECORD=41|OwnerIndex=570|IndexInSheet=39|OwnerPartId=-1|Location.X=358|Location.Y=237|Color=8388608|FontID=1|IsHidden=T|Text=100mW|Name=Power Rating
|RECORD=41|OwnerIndex=570|IndexInSheet=40|OwnerPartId=-1|Location.X=358|Location.Y=237|Color=8388608|FontID=1|IsHidden=T|Text=2|Name=Number of Pins
|RECORD=41|OwnerIndex=570|IndexInSheet=41|OwnerPartId=-1|Location.X=358|Location.Y=237|Color=8388608|FontID=1|IsHidden=T|Text=1%|Name=Tolerance
|RECORD=34|OwnerIndex=570|IndexInSheet=-1|OwnerPartId=-1|Location.X=370|Location.Y=209|Color=8388608|FontID=1|Text=R40|Name=Designator|ReadOnlyState=1
|RECORD=41|OwnerIndex=570|IndexInSheet=-1|OwnerPartId=1|Location.X=370|Location.Y=199|Color=8388608|FontID=1|Text=DNI_100k|Name=Comment
|RECORD=44|OwnerIndex=570
|RECORD=45|OwnerIndex=617|IndexInSheet=-1|UseComponentLibrary=T|ModelName=FP-RC0603-0_55-MFG|ModelType=PCBLIB|DatafileCount=1|ModelDatafileEntity0=FP-RC0603-0_55-MFG|ModelDatafileKind0=PCBLib|IsCurrent=T|DatalinksLocked=T|DatabaseDatalinksLocked=T
|RECORD=46|OwnerIndex=618
|RECORD=48|OwnerIndex=618
|RECORD=45|OwnerIndex=617|IndexInSheet=-1|UseComponentLibrary=T|ModelName=FP-RC0603-0_55-IPC_C|ModelType=PCBLIB|DatafileCount=1|ModelDatafileEntity0=FP-RC0603-0_55-IPC_C|ModelDatafileKind0=PCBLib|DatalinksLocked=T|DatabaseDatalinksLocked=T
|RECORD=46|OwnerIndex=621
|RECORD=48|OwnerIndex=621
|RECORD=45|OwnerIndex=617|IndexInSheet=-1|UseComponentLibrary=T|ModelName=FP-RC0603-0_55-IPC_B|ModelType=PCBLIB|DatafileCount=1|ModelDatafileEntity0=FP-RC0603-0_55-IPC_B|ModelDatafileKind0=PCBLib|DatalinksLocked=T|DatabaseDatalinksLocked=T
|RECORD=46|OwnerIndex=624
|RECORD=48|OwnerIndex=624
|RECORD=45|OwnerIndex=617|IndexInSheet=-1|UseComponentLibrary=T|ModelName=FP-RC0603-0_55-IPC_A|ModelType=PCBLIB|DatafileCount=1|ModelDatafileEntity0=FP-RC0603-0_55-IPC_A|ModelDatafileKind0=PCBLib|DatalinksLocked=T|DatabaseDatalinksLocked=T
|RECORD=46|OwnerIndex=627
|RECORD=48|OwnerIndex=627
|RECORD=17|IndexInSheet=32|OwnerPartId=-1|Style=4|ShowNetName=T|Location.X=534|Location.Y=155|Orientation=3|Color=128|FontID=1|Text=GND
|RECORD=17|IndexInSheet=33|OwnerPartId=-1|Style=4|ShowNetName=T|Location.X=444|Location.Y=155|Orientation=3|Color=128|FontID=1|Text=GND
|RECORD=17|IndexInSheet=34|OwnerPartId=-1|Style=4|ShowNetName=T|Location.X=614|Location.Y=155|Orientation=3|Color=128|FontID=1|Text=GND
|RECORD=17|IndexInSheet=35|OwnerPartId=-1|Style=4|ShowNetName=T|Location.X=364|Location.Y=155|Orientation=3|Color=128|FontID=1|Text=GND
|RECORD=17|IndexInSheet=36|OwnerPartId=-1|ShowNetName=T|Location.X=464|Location.Y=465|Orientation=1|Color=128|FontID=1|Text=+3.3V
|RECORD=17|IndexInSheet=37|OwnerPartId=-1|ShowNetName=T|Location.X=494|Location.Y=490|Orientation=1|Color=128|FontID=1|Text=+3.3V
|RECORD=4|IndexInSheet=38|OwnerPartId=-1|Location.X=764|Location.Y=555|Color=8388608|FontID=8|Text=LED DRIVER (0x6E)
|RECORD=17|IndexInSheet=39|OwnerPartId=-1|ShowNetName=T|Location.X=584|Location.Y=445|Orientation=2|Color=255|FontID=1|Text=SDA|IsCrossSheetConnector=T
|RECORD=17|IndexInSheet=40|OwnerPartId=-1|ShowNetName=T|Location.X=579|Location.Y=435|Orientation=2|Color=255|FontID=1|Text=SCL|IsCrossSheetConnector=T
|RECORD=1|LibReference=RES-2|ComponentDescription=Precision Thick Film Chip Resistor, 4.7 KOhm, +/- 1%, -55 to 155 degC, 0603 (1608 Metric), RoHS, Tape and Reel ERJ-3EKF4701V|PartCount=2|DisplayModeCount=1|IndexInSheet=41|OwnerPartId=-1|Location.X=564|Location.Y=185|Orientation=1|CurrentPartId=1|LibraryPath=*|SourceLibraryName=Altium Content Vault|TargetFileName=*|AreaColor=11599871|Color=128|PartIDLocked=T|DesignItemId=CMP-1012-00586-3|AllPinCount=2
|RECORD=2|OwnerIndex=639|OwnerPartId=1|FormalType=1|Electrical=4|PinConglomerate=33|PinLength=10|Location.X=564|Location.Y=205|Name=2|Designator=2|PinPropagationDelay=0.000000E+000
|RECORD=2|OwnerIndex=639|OwnerPartId=1|FormalType=1|Electrical=4|PinConglomerate=35|PinLength=10|Location.X=564|Location.Y=185|Name=1|Designator=1|PinPropagationDelay=0.000000E+000
|RECORD=6|OwnerIndex=639|IsNotAccesible=T|IndexInSheet=2|OwnerPartId=1|LineWidth=1|Color=16711680|LocationCount=10|X1=564|Y1=205|X2=564|Y2=201|X3=566|Y3=200|X4=562|Y4=198|X5=566|Y5=196|X6=562|Y6=194|X7=566|Y7=192|X8=562|Y8=190|X9=564|Y9=189|X10=564|Y10=185
|RECORD=41|OwnerIndex=639|IndexInSheet=3|OwnerPartId=-1|Location.X=561|Location.Y=217|Color=8388608|FontID=1|IsHidden=T|Text=220 Ohm|Name=Resistance
|RECORD=41|OwnerIndex=639|IndexInSheet=4|OwnerPartId=-1|Location.X=561|Location.Y=217|Color=8388608|FontID=1|IsHidden=T|Text=0603|Name=PackageReference
|RECORD=41|OwnerIndex=639|IndexInSheet=5|OwnerPartId=-1|Location.X=561|Location.Y=217|Color=8388608|FontID=1|IsHidden=T|Text=50 V|Name=Voltage Rating
|RECORD=41|OwnerIndex=639|IndexInSheet=6|OwnerPartId=-1|Location.X=561|Location.Y=217|Color=8388608|FontID=1|IsHidden=T|Text=125 degC|Name=Max Operating Temperature
|RECORD=41|OwnerIndex=639|IndexInSheet=7|OwnerPartId=-1|Location.X=561|Location.Y=217|Color=8388608|FontID=1|IsHidden=T|Text=4|Name=Elements
|RECORD=41|OwnerIndex=639|IndexInSheet=8|OwnerPartId=-1|Location.X=561|Location.Y=217|Color=8388608|FontID=1|IsHidden=T|Text=No SVHC|Name=REACH SVHC
|RECORD=41|OwnerIndex=639|IndexInSheet=9|OwnerPartId=-1|Location.X=561|Location.Y=217|Color=8388608|FontID=1|IsHidden=T|Text=0.063 inch|Name=Width
|RECORD=41|OwnerIndex=639|IndexInSheet=10|OwnerPartId=-1|Location.X=561|Location.Y=217|Color=8388608|FontID=1|IsHidden=T|Text=1205|Name=Case\Package
|RECORD=41|OwnerIndex=639|IndexInSheet=11|OwnerPartId=-1|Location.X=561|Location.Y=217|Color=8388608|FontID=1|IsHidden=T|Text=0.126 inch|Name=Length
|RECORD=41|OwnerIndex=639|IndexInSheet=12|OwnerPartId=-1|Location.X=561|Location.Y=217|Color=8388608|FontID=1|IsHidden=T|Text=0.024 inch|Name=Height
|RECORD=41|OwnerIndex=639|IndexInSheet=13|OwnerPartId=-1|Location.X=561|Location.Y=217|Color=8388608|FontID=1|IsHidden=T|Text=Surface Mount|Name=Mount
|RECORD=41|OwnerIndex=639|IndexInSheet=14|OwnerPartId=-1|Location.X=561|Location.Y=217|Color=8388608|FontID=1|IsHidden=T|Text=1|Name=Package Quantity
|RECORD=41|OwnerIndex=639|IndexInSheet=15|OwnerPartId=-1|Location.X=561|Location.Y=217|Color=8388608|FontID=1|IsHidden=T|Text=Apr-15|Name=DatasheetVersion
|RECORD=41|OwnerIndex=639|IndexInSheet=16|OwnerPartId=-1|Location.X=561|Location.Y=217|Color=8388608|FontID=1|IsHidden=T|Text=Manufacturer URL|Name=ComponentLink1Description
|RECORD=41|OwnerIndex=639|IndexInSheet=17|OwnerPartId=-1|Location.X=561|Location.Y=217|Color=8388608|FontID=1|IsHidden=T|Text=-55 degC|Name=Min Operating Temperature
|RECORD=41|OwnerIndex=639|IndexInSheet=18|OwnerPartId=-1|Location.X=561|Location.Y=217|Color=8388608|FontID=1|IsHidden=T|Text=Tape and Reel|Name=Packaging
|RECORD=41|OwnerIndex=639|IndexInSheet=19|OwnerPartId=-1|Location.X=561|Location.Y=217|Color=8388608|FontID=1|IsHidden=T|Text=No|Name=Radiation Hardening
|RECORD=41|OwnerIndex=639|IndexInSheet=20|OwnerPartId=-1|Location.X=561|Location.Y=217|Color=8388608|FontID=5|IsHidden=T|Text=http://industrial.panasonic.com/cdbs/www-data/pdf/RDA0000/AOA0000C86.pdf|Name=ComponentLink2URL
|RECORD=41|OwnerIndex=639|IndexInSheet=21|OwnerPartId=-1|Location.X=561|Location.Y=217|Color=8388608|FontID=1|IsHidden=T|Text=3216|Name=Case Code (Metric)
|RECORD=41|OwnerIndex=639|IndexInSheet=22|OwnerPartId=-1|Location.X=561|Location.Y=217|Color=8388608|FontID=1|IsHidden=T|Text=8|Name=Pins
|RECORD=41|OwnerIndex=639|IndexInSheet=23|OwnerPartId=-1|Location.X=561|Location.Y=217|Color=8388608|FontID=1|IsHidden=T|Text=1206|Name=Case Code (Imperial)
|RECORD=41|OwnerIndex=639|IndexInSheet=24|OwnerPartId=-1|Location.X=561|Location.Y=217|Color=8388608|FontID=1|IsHidden=T|Text=Thick Film|Name=Type (Resistor)
|RECORD=41|OwnerIndex=639|IndexInSheet=25|OwnerPartId=-1|Location.X=561|Location.Y=217|Color=8388608|FontID=1|IsHidden=T|Text=true|Name=RoHSCompliant
|RECORD=41|OwnerIndex=639|IndexInSheet=26|OwnerPartId=-1|Location.X=561|Location.Y=217|Color=8388608|FontID=1|IsHidden=T|Text=5%|Name=Tolerance
|RECORD=41|OwnerIndex=639|IndexInSheet=27|OwnerPartId=-1|Location.X=561|Location.Y=217|Color=8388608|FontID=1|IsHidden=T|Text=Datasheet|Name=ComponentLink2Description
|RECORD=41|OwnerIndex=639|IndexInSheet=28|OwnerPartId=-1|Location.X=561|Location.Y=217|Color=8388608|FontID=1|IsHidden=T|Text=2-Pin Surface Mount Device, Body 1.6 x 0.85 mm|Name=PackageDescription
|RECORD=41|OwnerIndex=639|IndexInSheet=29|OwnerPartId=-1|Location.X=561|Location.Y=217|Color=8388608|FontID=5|IsHidden=T|Text=http://www.panasonic.com/|Name=ComponentLink1URL
|RECORD=41|OwnerIndex=639|IndexInSheet=30|OwnerPartId=-1|Location.X=561|Location.Y=217|Color=8388608|FontID=1|IsHidden=T|Text=250 mW|Name=Power Rating
|RECORD=34|OwnerIndex=639|IndexInSheet=-1|OwnerPartId=-1|Location.X=567|Location.Y=196|Color=8388608|FontID=1|Text=R41|Name=Designator|ReadOnlyState=1
|RECORD=41|OwnerIndex=639|IndexInSheet=-1|OwnerPartId=-1|Location.X=567|Location.Y=186|Color=8388608|FontID=1|Text=4.7K|Name=Comment
|RECORD=44|OwnerIndex=639
|RECORD=45|OwnerIndex=675|IndexInSheet=-1|Description=Chip Resistor, 2-Leads, Body 1.75x0.95mm, IPC Medium Density|UseComponentLibrary=T|ModelName=RESC1608X55X30NL15T15|ModelType=PCBLIB|DatafileCount=1|ModelDatafileEntity0=RESC1608X55X30NL15T15|ModelDatafileKind0=PCBLib|IsCurrent=T|DatalinksLocked=T|DatabaseDatalinksLocked=T
|RECORD=46|OwnerIndex=676
|RECORD=48|OwnerIndex=676
|RECORD=41|OwnerIndex=678|IndexInSheet=-1|OwnerPartId=-1|Color=8388608|FontID=1|IsHidden=T|Text=2D|Name=Available Preview Images
|RECORD=45|OwnerIndex=675|IndexInSheet=-1|Description=Chip Resistor, 2-Leads, Body 1.75x0.95mm, IPC Low Density|UseComponentLibrary=T|ModelName=RESC1608X55X30ML15T15|ModelType=PCBLIB|DatafileCount=1|ModelDatafileEntity0=RESC1608X55X30ML15T15|ModelDatafileKind0=PCBLib|DatalinksLocked=T|DatabaseDatalinksLocked=T
|RECORD=46|OwnerIndex=680
|RECORD=48|OwnerIndex=680
|RECORD=41|OwnerIndex=682|IndexInSheet=-1|OwnerPartId=-1|Color=8388608|FontID=1|IsHidden=T|Text=2D|Name=Available Preview Images
|RECORD=45|OwnerIndex=675|IndexInSheet=-1|Description=Chip Resistor, 2-Leads, Body 1.75x0.95mm, IPC High Density|UseComponentLibrary=T|ModelName=RESC1608X55X30LL15T15|ModelType=PCBLIB|DatafileCount=1|ModelDatafileEntity0=RESC1608X55X30LL15T15|ModelDatafileKind0=PCBLib|DatalinksLocked=T|DatabaseDatalinksLocked=T
|RECORD=46|OwnerIndex=684
|RECORD=48|OwnerIndex=684
|RECORD=41|OwnerIndex=686|IndexInSheet=-1|OwnerPartId=-1|Color=8388608|FontID=1|IsHidden=T|Text=2D|Name=Available Preview Images
|RECORD=17|IndexInSheet=42|OwnerPartId=-1|Style=4|ShowNetName=T|Location.X=564|Location.Y=155|Orientation=3|Color=128|FontID=1|Text=GND
|RECORD=41|IndexInSheet=43|OwnerPartId=-1|Color=8388608|FontID=1|IsHidden=T|Name=ConfigurationParameters|ReadOnlyState=1
|RECORD=41|IndexInSheet=44|OwnerPartId=-1|Color=8388608|FontID=1|IsHidden=T|Name=ConfiguratorName|ReadOnlyState=1
|RECORD=41|IndexInSheet=45|OwnerPartId=-1|Color=8388608|FontID=1|IsHidden=T|Name=VersionControl_RevNumber|ReadOnlyState=1
|RECORD=41|IndexInSheet=46|OwnerPartId=-1|Color=8388608|FontID=1|IsHidden=T|Name=IsUserConfigurable|ReadOnlyState=1
|RECORD=41|IndexInSheet=47|OwnerPartId=-1|Color=8388608|FontID=1|IsHidden=T|Name=VersionControl_ProjFolderRevNumber|ReadOnlyState=1
|RECORD=41|IndexInSheet=48|OwnerPartId=-1|Color=8388608|FontID=1|IsHidden=T|Name=SPICEModelCache|ReadOnlyState=1
|RECORD=1|LibReference=8706943c75ba83719d021d2fdc84c58|ComponentDescription=LED BLUE CLEAR CHIP SMD|PartCount=2|DisplayModeCount=1|IndexInSheet=49|OwnerPartId=-1|Location.X=581|Location.Y=799|Orientation=3|CurrentPartId=1|LibraryPath=*|SourceLibraryName=Altium Content Vault|TargetFileName=*|AreaColor=11599871|Color=128|PartIDLocked=T|DesignItemId=CMP-22017-000008-1|AllPinCount=2
|RECORD=2|OwnerIndex=695|OwnerPartId=1|Electrical=4|PinConglomerate=33|PinLength=20|Location.X=581|Location.Y=779|Name=A|Designator=2|PinPropagationDelay=0.000000E+000
|RECORD=2|OwnerIndex=695|OwnerPartId=1|Electrical=4|PinConglomerate=35|PinLength=20|Location.X=581|Location.Y=759|Name=C|Designator=1|PinPropagationDelay=0.000000E+000
|RECORD=13|OwnerIndex=695|IsNotAccesible=T|IndexInSheet=2|OwnerPartId=1|Location.X=591|Location.Y=779|Corner.X=571|Corner.Y=779|LineWidth=1|Color=16711680
|RECORD=13|OwnerIndex=695|IsNotAccesible=T|IndexInSheet=3|OwnerPartId=1|Location.X=591|Location.Y=759|Corner.X=571|Corner.Y=759|LineWidth=1|Color=16711680
|RECORD=13|OwnerIndex=695|IsNotAccesible=T|IndexInSheet=4|OwnerPartId=1|Location.X=591|Location.Y=779|Corner.X=581|Corner.Y=759|LineWidth=1|Color=16711680
|RECORD=13|OwnerIndex=695|IsNotAccesible=T|IndexInSheet=5|OwnerPartId=1|Location.X=571|Location.Y=779|Corner.X=581|Corner.Y=759|LineWidth=1|Color=16711680
|RECORD=13|OwnerIndex=695|IsNotAccesible=T|IndexInSheet=6|OwnerPartId=1|Location.X=593|Location.Y=774|Corner.X=603|Corner.Y=764|LineWidth=1|Color=16711680
|RECORD=13|OwnerIndex=695|IsNotAccesible=T|IndexInSheet=7|OwnerPartId=1|Location.X=603|Location.Y=764|Corner.X=603|Corner.Y=769|LineWidth=1|Color=16711680
|RECORD=13|OwnerIndex=695|IsNotAccesible=T|IndexInSheet=8|OwnerPartId=1|Location.X=603|Location.Y=764|Corner.X=598|Corner.Y=764|LineWidth=1|Color=16711680
|RECORD=13|OwnerIndex=695|IsNotAccesible=T|IndexInSheet=9|OwnerPartId=1|Location.X=589|Location.Y=767|Corner.X=599|Corner.Y=757|LineWidth=1|Color=16711680
|RECORD=13|OwnerIndex=695|IsNotAccesible=T|IndexInSheet=10|OwnerPartId=1|Location.X=599|Location.Y=757|Corner.X=599|Corner.Y=762|LineWidth=1|Color=16711680
|RECORD=13|OwnerIndex=695|IsNotAccesible=T|IndexInSheet=11|OwnerPartId=1|Location.X=599|Location.Y=757|Corner.X=594|Corner.Y=757|LineWidth=1|Color=16711680
|RECORD=13|OwnerIndex=695|IsNotAccesible=T|IndexInSheet=12|OwnerPartId=1|Location.X=581|Location.Y=779|Corner.X=581|Corner.Y=782|LineWidth=1|Color=16711680
|RECORD=13|OwnerIndex=695|IsNotAccesible=T|IndexInSheet=13|OwnerPartId=1|Location.X=581|Location.Y=759|Corner.X=581|Corner.Y=756|LineWidth=1|Color=16711680
|RECORD=41|OwnerIndex=695|IndexInSheet=14|OwnerPartId=-1|Location.X=570|Location.Y=801|Color=8388608|FontID=1|IsHidden=T|Text=Colorless|Name=Lens Color
|RECORD=41|OwnerIndex=695|IndexInSheet=15|OwnerPartId=-1|Location.X=570|Location.Y=801|Color=8388608|FontID=1|IsHidden=T|Text=1608|Name=Case Code (Metric)
|RECORD=41|OwnerIndex=695|IndexInSheet=16|OwnerPartId=-1|Location.X=570|Location.Y=801|Color=8388608|FontID=1|IsHidden=T|Text=Tape and Reel|Name=Packaging
|RECORD=41|OwnerIndex=695|IndexInSheet=17|OwnerPartId=-1|Location.X=570|Location.Y=801|Color=8388608|FontID=1|IsHidden=T|Text=0603|Name=Case/Package
|RECORD=41|OwnerIndex=695|IndexInSheet=18|OwnerPartId=-1|Location.X=570|Location.Y=801|Color=8388608|FontID=1|IsHidden=T|Text=1.6mm|Name=Depth
|RECORD=41|OwnerIndex=695|IndexInSheet=19|OwnerPartId=-1|Location.X=570|Location.Y=801|Color=8388608|FontID=1|IsHidden=T|Text=475nm|Name=Dominant Wavelength
|RECORD=41|OwnerIndex=695|IndexInSheet=20|OwnerPartId=-1|Location.X=570|Location.Y=801|Color=8388608|FontID=1|IsHidden=T|Text=Surface Mount|Name=Mount
|RECORD=41|OwnerIndex=695|IndexInSheet=21|OwnerPartId=-1|Location.X=570|Location.Y=801|Color=8388608|FontID=1|IsHidden=T|Text=20mA|Name=Forward Current
|RECORD=41|OwnerIndex=695|IndexInSheet=22|OwnerPartId=-1|Location.X=570|Location.Y=801|Color=8388608|FontID=1|IsHidden=T|Text=Lead Free|Name=Lead Free
|RECORD=41|OwnerIndex=695|IndexInSheet=23|OwnerPartId=-1|Location.X=570|Location.Y=801|Color=8388608|FontID=1|IsHidden=T|Text=468nm|Name=Wavelength
|RECORD=41|OwnerIndex=695|IndexInSheet=24|OwnerPartId=-1|Location.X=570|Location.Y=801|Color=8388608|FontID=1|IsHidden=T|Text=130°|Name=Viewing Angle
|RECORD=41|OwnerIndex=695|IndexInSheet=25|OwnerPartId=-1|Location.X=570|Location.Y=801|Color=8388608|FontID=1|IsHidden=T|Text=-20°C|Name=Min Operating Temperature
|RECORD=41|OwnerIndex=695|IndexInSheet=26|OwnerPartId=-1|Location.X=570|Location.Y=801|Color=8388608|FontID=1|IsHidden=T|Text=Clear|Name=Lens Transparency
|RECORD=41|OwnerIndex=695|IndexInSheet=27|OwnerPartId=-1|Location.X=570|Location.Y=801|Color=8388608|FontID=1|IsHidden=T|Text=76mW|Name=Power Dissipation
|RECORD=41|OwnerIndex=695|IndexInSheet=28|OwnerPartId=-1|Location.X=570|Location.Y=801|Color=8388608|FontID=1|IsHidden=T|Text=Blue|Name=Illumination Color
|RECORD=41|OwnerIndex=695|IndexInSheet=29|OwnerPartId=-1|Location.X=570|Location.Y=801|Color=8388608|FontID=1|IsHidden=T|Text=0.55mm|Name=Height
|RECORD=41|OwnerIndex=695|IndexInSheet=30|OwnerPartId=-1|Location.X=570|Location.Y=801|Color=8388608|FontID=1|IsHidden=T|Text=20mA|Name=Test Current
|RECORD=41|OwnerIndex=695|IndexInSheet=31|OwnerPartId=-1|Location.X=570|Location.Y=801|Color=8388608|FontID=1|IsHidden=T|Text=0603|Name=Case Code (Imperial)
|RECORD=41|OwnerIndex=695|IndexInSheet=32|OwnerPartId=-1|Location.X=570|Location.Y=801|Color=8388608|FontID=1|IsHidden=T|Text=180mcd|Name=Luminous Intensity
|RECORD=41|OwnerIndex=695|IndexInSheet=33|OwnerPartId=-1|Location.X=570|Location.Y=801|Color=8388608|FontID=1|IsHidden=T|Text=5V|Name=Reverse Voltage
|RECORD=41|OwnerIndex=695|IndexInSheet=34|OwnerPartId=-1|Location.X=570|Location.Y=801|Color=8388608|FontID=1|IsHidden=T|Text=80°C|Name=Max Operating Temperature
|RECORD=41|OwnerIndex=695|IndexInSheet=35|OwnerPartId=-1|Location.X=570|Location.Y=801|Color=8388608|FontID=1|IsHidden=T|Text=2|Name=Number of Pins
|RECORD=41|OwnerIndex=695|IndexInSheet=36|OwnerPartId=-1|Location.X=570|Location.Y=801|Color=8388608|FontID=1|IsHidden=T|Text=0.8mm|Name=Length
|RECORD=41|OwnerIndex=695|IndexInSheet=37|OwnerPartId=-1|Location.X=570|Location.Y=801|Color=8388608|FontID=1|IsHidden=T|Text=No|Name=Radiation Hardening
|RECORD=41|OwnerIndex=695|IndexInSheet=38|OwnerPartId=-1|Location.X=570|Location.Y=801|Color=8388608|FontID=1|IsHidden=T|Text=1|Name=Number of Elements
|RECORD=41|OwnerIndex=695|IndexInSheet=39|OwnerPartId=-1|Location.X=570|Location.Y=801|Color=8388608|FontID=1|IsHidden=T|Text=1|Name=Package Quantity
|RECORD=41|OwnerIndex=695|IndexInSheet=40|OwnerPartId=-1|Location.X=570|Location.Y=801|Color=8388608|FontID=1|IsHidden=T|Text=1|Name=Number of LEDs
|RECORD=41|OwnerIndex=695|IndexInSheet=41|OwnerPartId=-1|Location.X=570|Location.Y=801|Color=8388608|FontID=1|IsHidden=T|Text=Diffused|Name=Lens Style
|RECORD=41|OwnerIndex=695|IndexInSheet=42|OwnerPartId=-1|Location.X=570|Location.Y=801|Color=8388608|FontID=1|IsHidden=T|Text=3.8V|Name=Forward Voltage
|RECORD=41|OwnerIndex=695|IndexInSheet=43|OwnerPartId=-1|Location.X=570|Location.Y=801|Color=8388608|FontID=1|IsHidden=T|Text=0.8mm|Name=Width
|RECORD=41|OwnerIndex=695|IndexInSheet=44|OwnerPartId=-1|Location.X=570|Location.Y=801|Color=8388608|FontID=1|IsHidden=T|Text=75mW|Name=Max Power Dissipation
|RECORD=41|OwnerIndex=695|IndexInSheet=45|OwnerPartId=-1|Location.X=570|Location.Y=801|Color=8388608|FontID=1|IsHidden=T|Text=Blue|Name=Color
|RECORD=34|OwnerIndex=695|IndexInSheet=-1|OwnerPartId=-1|Location.X=604|Location.Y=773|Color=8388608|FontID=1|Text=D3|Name=Designator|ReadOnlyState=1
|RECORD=41|OwnerIndex=695|IndexInSheet=-1|OwnerPartId=1|Location.X=604|Location.Y=763|Color=8388608|FontID=1|Text=BLUE|Name=Comment
|RECORD=44|OwnerIndex=695
|RECORD=45|OwnerIndex=746|IndexInSheet=-1|UseComponentLibrary=T|ModelName=FP-LTST-C191TBKT-MFG|ModelType=PCBLIB|DatafileCount=1|ModelDatafileEntity0=FP-LTST-C191TBKT-MFG|ModelDatafileKind0=PCBLib|IsCurrent=T|DatalinksLocked=T|DatabaseDatalinksLocked=T
|RECORD=46|OwnerIndex=747
|RECORD=48|OwnerIndex=747
|RECORD=1|LibReference=8706943c75ba83719d021d2fdc84c58|ComponentDescription=LED BLUE CLEAR CHIP SMD|PartCount=2|DisplayModeCount=1|IndexInSheet=50|OwnerPartId=-1|Location.X=681|Location.Y=799|Orientation=3|CurrentPartId=1|LibraryPath=*|SourceLibraryName=Altium Content Vault|TargetFileName=*|AreaColor=11599871|Color=128|PartIDLocked=T|DesignItemId=CMP-22017-000008-1|AllPinCount=2
|RECORD=2|OwnerIndex=750|OwnerPartId=1|Electrical=4|PinConglomerate=33|PinLength=20|Location.X=681|Location.Y=779|Name=A|Designator=2|PinPropagationDelay=0.000000E+000
|RECORD=2|OwnerIndex=750|OwnerPartId=1|Electrical=4|PinConglomerate=35|PinLength=20|Location.X=681|Location.Y=759|Name=C|Designator=1|PinPropagationDelay=0.000000E+000
|RECORD=13|OwnerIndex=750|IsNotAccesible=T|IndexInSheet=2|OwnerPartId=1|Location.X=691|Location.Y=779|Corner.X=671|Corner.Y=779|LineWidth=1|Color=16711680
|RECORD=13|OwnerIndex=750|IsNotAccesible=T|IndexInSheet=3|OwnerPartId=1|Location.X=691|Location.Y=759|Corner.X=671|Corner.Y=759|LineWidth=1|Color=16711680
|RECORD=13|OwnerIndex=750|IsNotAccesible=T|IndexInSheet=4|OwnerPartId=1|Location.X=691|Location.Y=779|Corner.X=681|Corner.Y=759|LineWidth=1|Color=16711680
|RECORD=13|OwnerIndex=750|IsNotAccesible=T|IndexInSheet=5|OwnerPartId=1|Location.X=671|Location.Y=779|Corner.X=681|Corner.Y=759|LineWidth=1|Color=16711680
|RECORD=13|OwnerIndex=750|IsNotAccesible=T|IndexInSheet=6|OwnerPartId=1|Location.X=693|Location.Y=774|Corner.X=703|Corner.Y=764|LineWidth=1|Color=16711680
|RECORD=13|OwnerIndex=750|IsNotAccesible=T|IndexInSheet=7|OwnerPartId=1|Location.X=703|Location.Y=764|Corner.X=703|Corner.Y=769|LineWidth=1|Color=16711680
|RECORD=13|OwnerIndex=750|IsNotAccesible=T|IndexInSheet=8|OwnerPartId=1|Location.X=703|Location.Y=764|Corner.X=698|Corner.Y=764|LineWidth=1|Color=16711680
|RECORD=13|OwnerIndex=750|IsNotAccesible=T|IndexInSheet=9|OwnerPartId=1|Location.X=689|Location.Y=767|Corner.X=699|Corner.Y=757|LineWidth=1|Color=16711680
|RECORD=13|OwnerIndex=750|IsNotAccesible=T|IndexInSheet=10|OwnerPartId=1|Location.X=699|Location.Y=757|Corner.X=699|Corner.Y=762|LineWidth=1|Color=16711680
|RECORD=13|OwnerIndex=750|IsNotAccesible=T|IndexInSheet=11|OwnerPartId=1|Location.X=699|Location.Y=757|Corner.X=694|Corner.Y=757|LineWidth=1|Color=16711680
|RECORD=13|OwnerIndex=750|IsNotAccesible=T|IndexInSheet=12|OwnerPartId=1|Location.X=681|Location.Y=779|Corner.X=681|Corner.Y=782|LineWidth=1|Color=16711680
|RECORD=13|OwnerIndex=750|IsNotAccesible=T|IndexInSheet=13|OwnerPartId=1|Location.X=681|Location.Y=759|Corner.X=681|Corner.Y=756|LineWidth=1|Color=16711680
|RECORD=41|OwnerIndex=750|IndexInSheet=14|OwnerPartId=-1|Location.X=670|Location.Y=801|Color=8388608|FontID=1|IsHidden=T|Text=Colorless|Name=Lens Color
|RECORD=41|OwnerIndex=750|IndexInSheet=15|OwnerPartId=-1|Location.X=670|Location.Y=801|Color=8388608|FontID=1|IsHidden=T|Text=1608|Name=Case Code (Metric)
|RECORD=41|OwnerIndex=750|IndexInSheet=16|OwnerPartId=-1|Location.X=670|Location.Y=801|Color=8388608|FontID=1|IsHidden=T|Text=Tape and Reel|Name=Packaging
|RECORD=41|OwnerIndex=750|IndexInSheet=17|OwnerPartId=-1|Location.X=670|Location.Y=801|Color=8388608|FontID=1|IsHidden=T|Text=0603|Name=Case/Package
|RECORD=41|OwnerIndex=750|IndexInSheet=18|OwnerPartId=-1|Location.X=670|Location.Y=801|Color=8388608|FontID=1|IsHidden=T|Text=1.6mm|Name=Depth
|RECORD=41|OwnerIndex=750|IndexInSheet=19|OwnerPartId=-1|Location.X=670|Location.Y=801|Color=8388608|FontID=1|IsHidden=T|Text=475nm|Name=Dominant Wavelength
|RECORD=41|OwnerIndex=750|IndexInSheet=20|OwnerPartId=-1|Location.X=670|Location.Y=801|Color=8388608|FontID=1|IsHidden=T|Text=Surface Mount|Name=Mount
|RECORD=41|OwnerIndex=750|IndexInSheet=21|OwnerPartId=-1|Location.X=670|Location.Y=801|Color=8388608|FontID=1|IsHidden=T|Text=20mA|Name=Forward Current
|RECORD=41|OwnerIndex=750|IndexInSheet=22|OwnerPartId=-1|Location.X=670|Location.Y=801|Color=8388608|FontID=1|IsHidden=T|Text=Lead Free|Name=Lead Free
|RECORD=41|OwnerIndex=750|IndexInSheet=23|OwnerPartId=-1|Location.X=670|Location.Y=801|Color=8388608|FontID=1|IsHidden=T|Text=468nm|Name=Wavelength
|RECORD=41|OwnerIndex=750|IndexInSheet=24|OwnerPartId=-1|Location.X=670|Location.Y=801|Color=8388608|FontID=1|IsHidden=T|Text=130°|Name=Viewing Angle
|RECORD=41|OwnerIndex=750|IndexInSheet=25|OwnerPartId=-1|Location.X=670|Location.Y=801|Color=8388608|FontID=1|IsHidden=T|Text=-20°C|Name=Min Operating Temperature
|RECORD=41|OwnerIndex=750|IndexInSheet=26|OwnerPartId=-1|Location.X=670|Location.Y=801|Color=8388608|FontID=1|IsHidden=T|Text=Clear|Name=Lens Transparency
|RECORD=41|OwnerIndex=750|IndexInSheet=27|OwnerPartId=-1|Location.X=670|Location.Y=801|Color=8388608|FontID=1|IsHidden=T|Text=76mW|Name=Power Dissipation
|RECORD=41|OwnerIndex=750|IndexInSheet=28|OwnerPartId=-1|Location.X=670|Location.Y=801|Color=8388608|FontID=1|IsHidden=T|Text=Blue|Name=Illumination Color
|RECORD=41|OwnerIndex=750|IndexInSheet=29|OwnerPartId=-1|Location.X=670|Location.Y=801|Color=8388608|FontID=1|IsHidden=T|Text=0.55mm|Name=Height
|RECORD=41|OwnerIndex=750|IndexInSheet=30|OwnerPartId=-1|Location.X=670|Location.Y=801|Color=8388608|FontID=1|IsHidden=T|Text=20mA|Name=Test Current
|RECORD=41|OwnerIndex=750|IndexInSheet=31|OwnerPartId=-1|Location.X=670|Location.Y=801|Color=8388608|FontID=1|IsHidden=T|Text=0603|Name=Case Code (Imperial)
|RECORD=41|OwnerIndex=750|IndexInSheet=32|OwnerPartId=-1|Location.X=670|Location.Y=801|Color=8388608|FontID=1|IsHidden=T|Text=180mcd|Name=Luminous Intensity
|RECORD=41|OwnerIndex=750|IndexInSheet=33|OwnerPartId=-1|Location.X=670|Location.Y=801|Color=8388608|FontID=1|IsHidden=T|Text=5V|Name=Reverse Voltage
|RECORD=41|OwnerIndex=750|IndexInSheet=34|OwnerPartId=-1|Location.X=670|Location.Y=801|Color=8388608|FontID=1|IsHidden=T|Text=80°C|Name=Max Operating Temperature
|RECORD=41|OwnerIndex=750|IndexInSheet=35|OwnerPartId=-1|Location.X=670|Location.Y=801|Color=8388608|FontID=1|IsHidden=T|Text=2|Name=Number of Pins
|RECORD=41|OwnerIndex=750|IndexInSheet=36|OwnerPartId=-1|Location.X=670|Location.Y=801|Color=8388608|FontID=1|IsHidden=T|Text=0.8mm|Name=Length
|RECORD=41|OwnerIndex=750|IndexInSheet=37|OwnerPartId=-1|Location.X=670|Location.Y=801|Color=8388608|FontID=1|IsHidden=T|Text=No|Name=Radiation Hardening
|RECORD=41|OwnerIndex=750|IndexInSheet=38|OwnerPartId=-1|Location.X=670|Location.Y=801|Color=8388608|FontID=1|IsHidden=T|Text=1|Name=Number of Elements
|RECORD=41|OwnerIndex=750|IndexInSheet=39|OwnerPartId=-1|Location.X=670|Location.Y=801|Color=8388608|FontID=1|IsHidden=T|Text=1|Name=Package Quantity
|RECORD=41|OwnerIndex=750|IndexInSheet=40|OwnerPartId=-1|Location.X=670|Location.Y=801|Color=8388608|FontID=1|IsHidden=T|Text=1|Name=Number of LEDs
|RECORD=41|OwnerIndex=750|IndexInSheet=41|OwnerPartId=-1|Location.X=670|Location.Y=801|Color=8388608|FontID=1|IsHidden=T|Text=Diffused|Name=Lens Style
|RECORD=41|OwnerIndex=750|IndexInSheet=42|OwnerPartId=-1|Location.X=670|Location.Y=801|Color=8388608|FontID=1|IsHidden=T|Text=3.8V|Name=Forward Voltage
|RECORD=41|OwnerIndex=750|IndexInSheet=43|OwnerPartId=-1|Location.X=670|Location.Y=801|Color=8388608|FontID=1|IsHidden=T|Text=0.8mm|Name=Width
|RECORD=41|OwnerIndex=750|IndexInSheet=44|OwnerPartId=-1|Location.X=670|Location.Y=801|Color=8388608|FontID=1|IsHidden=T|Text=75mW|Name=Max Power Dissipation
|RECORD=41|OwnerIndex=750|IndexInSheet=45|OwnerPartId=-1|Location.X=670|Location.Y=801|Color=8388608|FontID=1|IsHidden=T|Text=Blue|Name=Color
|RECORD=34|OwnerIndex=750|IndexInSheet=-1|OwnerPartId=-1|Location.X=704|Location.Y=773|Color=8388608|FontID=1|Text=D9|Name=Designator|ReadOnlyState=1
|RECORD=41|OwnerIndex=750|IndexInSheet=-1|OwnerPartId=1|Location.X=704|Location.Y=763|Color=8388608|FontID=1|Text=BLUE|Name=Comment
|RECORD=44|OwnerIndex=750
|RECORD=45|OwnerIndex=801|IndexInSheet=-1|UseComponentLibrary=T|ModelName=FP-LTST-C191TBKT-MFG|ModelType=PCBLIB|DatafileCount=1|ModelDatafileEntity0=FP-LTST-C191TBKT-MFG|ModelDatafileKind0=PCBLib|IsCurrent=T|DatalinksLocked=T|DatabaseDatalinksLocked=T
|RECORD=46|OwnerIndex=802
|RECORD=48|OwnerIndex=802
|RECORD=1|LibReference=8706943c75ba83719d021d2fdc84c58|ComponentDescription=LED BLUE CLEAR CHIP SMD|PartCount=2|DisplayModeCount=1|IndexInSheet=51|OwnerPartId=-1|Location.X=781|Location.Y=799|Orientation=3|CurrentPartId=1|LibraryPath=*|SourceLibraryName=Altium Content Vault|TargetFileName=*|AreaColor=11599871|Color=128|PartIDLocked=T|DesignItemId=CMP-22017-000008-1|AllPinCount=2
|RECORD=2|OwnerIndex=805|OwnerPartId=1|Electrical=4|PinConglomerate=33|PinLength=20|Location.X=781|Location.Y=779|Name=A|Designator=2|PinPropagationDelay=0.000000E+000
|RECORD=2|OwnerIndex=805|OwnerPartId=1|Electrical=4|PinConglomerate=35|PinLength=20|Location.X=781|Location.Y=759|Name=C|Designator=1|PinPropagationDelay=0.000000E+000
|RECORD=13|OwnerIndex=805|IsNotAccesible=T|IndexInSheet=2|OwnerPartId=1|Location.X=791|Location.Y=779|Corner.X=771|Corner.Y=779|LineWidth=1|Color=16711680
|RECORD=13|OwnerIndex=805|IsNotAccesible=T|IndexInSheet=3|OwnerPartId=1|Location.X=791|Location.Y=759|Corner.X=771|Corner.Y=759|LineWidth=1|Color=16711680
|RECORD=13|OwnerIndex=805|IsNotAccesible=T|IndexInSheet=4|OwnerPartId=1|Location.X=791|Location.Y=779|Corner.X=781|Corner.Y=759|LineWidth=1|Color=16711680
|RECORD=13|OwnerIndex=805|IsNotAccesible=T|IndexInSheet=5|OwnerPartId=1|Location.X=771|Location.Y=779|Corner.X=781|Corner.Y=759|LineWidth=1|Color=16711680
|RECORD=13|OwnerIndex=805|IsNotAccesible=T|IndexInSheet=6|OwnerPartId=1|Location.X=793|Location.Y=774|Corner.X=803|Corner.Y=764|LineWidth=1|Color=16711680
|RECORD=13|OwnerIndex=805|IsNotAccesible=T|IndexInSheet=7|OwnerPartId=1|Location.X=803|Location.Y=764|Corner.X=803|Corner.Y=769|LineWidth=1|Color=16711680
|RECORD=13|OwnerIndex=805|IsNotAccesible=T|IndexInSheet=8|OwnerPartId=1|Location.X=803|Location.Y=764|Corner.X=798|Corner.Y=764|LineWidth=1|Color=16711680
|RECORD=13|OwnerIndex=805|IsNotAccesible=T|IndexInSheet=9|OwnerPartId=1|Location.X=789|Location.Y=767|Corner.X=799|Corner.Y=757|LineWidth=1|Color=16711680
|RECORD=13|OwnerIndex=805|IsNotAccesible=T|IndexInSheet=10|OwnerPartId=1|Location.X=799|Location.Y=757|Corner.X=799|Corner.Y=762|LineWidth=1|Color=16711680
|RECORD=13|OwnerIndex=805|IsNotAccesible=T|IndexInSheet=11|OwnerPartId=1|Location.X=799|Location.Y=757|Corner.X=794|Corner.Y=757|LineWidth=1|Color=16711680
|RECORD=13|OwnerIndex=805|IsNotAccesible=T|IndexInSheet=12|OwnerPartId=1|Location.X=781|Location.Y=779|Corner.X=781|Corner.Y=782|LineWidth=1|Color=16711680
|RECORD=13|OwnerIndex=805|IsNotAccesible=T|IndexInSheet=13|OwnerPartId=1|Location.X=781|Location.Y=759|Corner.X=781|Corner.Y=756|LineWidth=1|Color=16711680
|RECORD=41|OwnerIndex=805|IndexInSheet=14|OwnerPartId=-1|Location.X=770|Location.Y=801|Color=8388608|FontID=1|IsHidden=T|Text=Colorless|Name=Lens Color
|RECORD=41|OwnerIndex=805|IndexInSheet=15|OwnerPartId=-1|Location.X=770|Location.Y=801|Color=8388608|FontID=1|IsHidden=T|Text=1608|Name=Case Code (Metric)
|RECORD=41|OwnerIndex=805|IndexInSheet=16|OwnerPartId=-1|Location.X=770|Location.Y=801|Color=8388608|FontID=1|IsHidden=T|Text=Tape and Reel|Name=Packaging
|RECORD=41|OwnerIndex=805|IndexInSheet=17|OwnerPartId=-1|Location.X=770|Location.Y=801|Color=8388608|FontID=1|IsHidden=T|Text=0603|Name=Case/Package
|RECORD=41|OwnerIndex=805|IndexInSheet=18|OwnerPartId=-1|Location.X=770|Location.Y=801|Color=8388608|FontID=1|IsHidden=T|Text=1.6mm|Name=Depth
|RECORD=41|OwnerIndex=805|IndexInSheet=19|OwnerPartId=-1|Location.X=770|Location.Y=801|Color=8388608|FontID=1|IsHidden=T|Text=475nm|Name=Dominant Wavelength
|RECORD=41|OwnerIndex=805|IndexInSheet=20|OwnerPartId=-1|Location.X=770|Location.Y=801|Color=8388608|FontID=1|IsHidden=T|Text=Surface Mount|Name=Mount
|RECORD=41|OwnerIndex=805|IndexInSheet=21|OwnerPartId=-1|Location.X=770|Location.Y=801|Color=8388608|FontID=1|IsHidden=T|Text=20mA|Name=Forward Current
|RECORD=41|OwnerIndex=805|IndexInSheet=22|OwnerPartId=-1|Location.X=770|Location.Y=801|Color=8388608|FontID=1|IsHidden=T|Text=Lead Free|Name=Lead Free
|RECORD=41|OwnerIndex=805|IndexInSheet=23|OwnerPartId=-1|Location.X=770|Location.Y=801|Color=8388608|FontID=1|IsHidden=T|Text=468nm|Name=Wavelength
|RECORD=41|OwnerIndex=805|IndexInSheet=24|OwnerPartId=-1|Location.X=770|Location.Y=801|Color=8388608|FontID=1|IsHidden=T|Text=130°|Name=Viewing Angle
|RECORD=41|OwnerIndex=805|IndexInSheet=25|OwnerPartId=-1|Location.X=770|Location.Y=801|Color=8388608|FontID=1|IsHidden=T|Text=-20°C|Name=Min Operating Temperature
|RECORD=41|OwnerIndex=805|IndexInSheet=26|OwnerPartId=-1|Location.X=770|Location.Y=801|Color=8388608|FontID=1|IsHidden=T|Text=Clear|Name=Lens Transparency
|RECORD=41|OwnerIndex=805|IndexInSheet=27|OwnerPartId=-1|Location.X=770|Location.Y=801|Color=8388608|FontID=1|IsHidden=T|Text=76mW|Name=Power Dissipation
|RECORD=41|OwnerIndex=805|IndexInSheet=28|OwnerPartId=-1|Location.X=770|Location.Y=801|Color=8388608|FontID=1|IsHidden=T|Text=Blue|Name=Illumination Color
|RECORD=41|OwnerIndex=805|IndexInSheet=29|OwnerPartId=-1|Location.X=770|Location.Y=801|Color=8388608|FontID=1|IsHidden=T|Text=0.55mm|Name=Height
|RECORD=41|OwnerIndex=805|IndexInSheet=30|OwnerPartId=-1|Location.X=770|Location.Y=801|Color=8388608|FontID=1|IsHidden=T|Text=20mA|Name=Test Current
|RECORD=41|OwnerIndex=805|IndexInSheet=31|OwnerPartId=-1|Location.X=770|Location.Y=801|Color=8388608|FontID=1|IsHidden=T|Text=0603|Name=Case Code (Imperial)
|RECORD=41|OwnerIndex=805|IndexInSheet=32|OwnerPartId=-1|Location.X=770|Location.Y=801|Color=8388608|FontID=1|IsHidden=T|Text=180mcd|Name=Luminous Intensity
|RECORD=41|OwnerIndex=805|IndexInSheet=33|OwnerPartId=-1|Location.X=770|Location.Y=801|Color=8388608|FontID=1|IsHidden=T|Text=5V|Name=Reverse Voltage
|RECORD=41|OwnerIndex=805|IndexInSheet=34|OwnerPartId=-1|Location.X=770|Location.Y=801|Color=8388608|FontID=1|IsHidden=T|Text=80°C|Name=Max Operating Temperature
|RECORD=41|OwnerIndex=805|IndexInSheet=35|OwnerPartId=-1|Location.X=770|Location.Y=801|Color=8388608|FontID=1|IsHidden=T|Text=2|Name=Number of Pins
|RECORD=41|OwnerIndex=805|IndexInSheet=36|OwnerPartId=-1|Location.X=770|Location.Y=801|Color=8388608|FontID=1|IsHidden=T|Text=0.8mm|Name=Length
|RECORD=41|OwnerIndex=805|IndexInSheet=37|OwnerPartId=-1|Location.X=770|Location.Y=801|Color=8388608|FontID=1|IsHidden=T|Text=No|Name=Radiation Hardening
|RECORD=41|OwnerIndex=805|IndexInSheet=38|OwnerPartId=-1|Location.X=770|Location.Y=801|Color=8388608|FontID=1|IsHidden=T|Text=1|Name=Number of Elements
|RECORD=41|OwnerIndex=805|IndexInSheet=39|OwnerPartId=-1|Location.X=770|Location.Y=801|Color=8388608|FontID=1|IsHidden=T|Text=1|Name=Package Quantity
|RECORD=41|OwnerIndex=805|IndexInSheet=40|OwnerPartId=-1|Location.X=770|Location.Y=801|Color=8388608|FontID=1|IsHidden=T|Text=1|Name=Number of LEDs
|RECORD=41|OwnerIndex=805|IndexInSheet=41|OwnerPartId=-1|Location.X=770|Location.Y=801|Color=8388608|FontID=1|IsHidden=T|Text=Diffused|Name=Lens Style
|RECORD=41|OwnerIndex=805|IndexInSheet=42|OwnerPartId=-1|Location.X=770|Location.Y=801|Color=8388608|FontID=1|IsHidden=T|Text=3.8V|Name=Forward Voltage
|RECORD=41|OwnerIndex=805|IndexInSheet=43|OwnerPartId=-1|Location.X=770|Location.Y=801|Color=8388608|FontID=1|IsHidden=T|Text=0.8mm|Name=Width
|RECORD=41|OwnerIndex=805|IndexInSheet=44|OwnerPartId=-1|Location.X=770|Location.Y=801|Color=8388608|FontID=1|IsHidden=T|Text=75mW|Name=Max Power Dissipation
|RECORD=41|OwnerIndex=805|IndexInSheet=45|OwnerPartId=-1|Location.X=770|Location.Y=801|Color=8388608|FontID=1|IsHidden=T|Text=Blue|Name=Color
|RECORD=34|OwnerIndex=805|IndexInSheet=-1|OwnerPartId=-1|Location.X=804|Location.Y=773|Color=8388608|FontID=1|Text=D10|Name=Designator|ReadOnlyState=1
|RECORD=41|OwnerIndex=805|IndexInSheet=-1|OwnerPartId=1|Location.X=804|Location.Y=763|Color=8388608|FontID=1|Text=BLUE|Name=Comment
|RECORD=44|OwnerIndex=805
|RECORD=45|OwnerIndex=856|IndexInSheet=-1|UseComponentLibrary=T|ModelName=FP-LTST-C191TBKT-MFG|ModelType=PCBLIB|DatafileCount=1|ModelDatafileEntity0=FP-LTST-C191TBKT-MFG|ModelDatafileKind0=PCBLib|IsCurrent=T|DatalinksLocked=T|DatabaseDatalinksLocked=T
|RECORD=46|OwnerIndex=857
|RECORD=48|OwnerIndex=857
|RECORD=1|LibReference=8706943c75ba83719d021d2fdc84c58|ComponentDescription=LED BLUE CLEAR CHIP SMD|PartCount=2|DisplayModeCount=1|IndexInSheet=52|OwnerPartId=-1|Location.X=881|Location.Y=799|Orientation=3|CurrentPartId=1|LibraryPath=*|SourceLibraryName=Altium Content Vault|TargetFileName=*|AreaColor=11599871|Color=128|PartIDLocked=T|DesignItemId=CMP-22017-000008-1|AllPinCount=2
|RECORD=2|OwnerIndex=860|OwnerPartId=1|Electrical=4|PinConglomerate=33|PinLength=20|Location.X=881|Location.Y=779|Name=A|Designator=2|PinPropagationDelay=0.000000E+000
|RECORD=2|OwnerIndex=860|OwnerPartId=1|Electrical=4|PinConglomerate=35|PinLength=20|Location.X=881|Location.Y=759|Name=C|Designator=1|PinPropagationDelay=0.000000E+000
|RECORD=13|OwnerIndex=860|IsNotAccesible=T|IndexInSheet=2|OwnerPartId=1|Location.X=891|Location.Y=779|Corner.X=871|Corner.Y=779|LineWidth=1|Color=16711680
|RECORD=13|OwnerIndex=860|IsNotAccesible=T|IndexInSheet=3|OwnerPartId=1|Location.X=891|Location.Y=759|Corner.X=871|Corner.Y=759|LineWidth=1|Color=16711680
|RECORD=13|OwnerIndex=860|IsNotAccesible=T|IndexInSheet=4|OwnerPartId=1|Location.X=891|Location.Y=779|Corner.X=881|Corner.Y=759|LineWidth=1|Color=16711680
|RECORD=13|OwnerIndex=860|IsNotAccesible=T|IndexInSheet=5|OwnerPartId=1|Location.X=871|Location.Y=779|Corner.X=881|Corner.Y=759|LineWidth=1|Color=16711680
|RECORD=13|OwnerIndex=860|IsNotAccesible=T|IndexInSheet=6|OwnerPartId=1|Location.X=893|Location.Y=774|Corner.X=903|Corner.Y=764|LineWidth=1|Color=16711680
|RECORD=13|OwnerIndex=860|IsNotAccesible=T|IndexInSheet=7|OwnerPartId=1|Location.X=903|Location.Y=764|Corner.X=903|Corner.Y=769|LineWidth=1|Color=16711680
|RECORD=13|OwnerIndex=860|IsNotAccesible=T|IndexInSheet=8|OwnerPartId=1|Location.X=903|Location.Y=764|Corner.X=898|Corner.Y=764|LineWidth=1|Color=16711680
|RECORD=13|OwnerIndex=860|IsNotAccesible=T|IndexInSheet=9|OwnerPartId=1|Location.X=889|Location.Y=767|Corner.X=899|Corner.Y=757|LineWidth=1|Color=16711680
|RECORD=13|OwnerIndex=860|IsNotAccesible=T|IndexInSheet=10|OwnerPartId=1|Location.X=899|Location.Y=757|Corner.X=899|Corner.Y=762|LineWidth=1|Color=16711680
|RECORD=13|OwnerIndex=860|IsNotAccesible=T|IndexInSheet=11|OwnerPartId=1|Location.X=899|Location.Y=757|Corner.X=894|Corner.Y=757|LineWidth=1|Color=16711680
|RECORD=13|OwnerIndex=860|IsNotAccesible=T|IndexInSheet=12|OwnerPartId=1|Location.X=881|Location.Y=779|Corner.X=881|Corner.Y=782|LineWidth=1|Color=16711680
|RECORD=13|OwnerIndex=860|IsNotAccesible=T|IndexInSheet=13|OwnerPartId=1|Location.X=881|Location.Y=759|Corner.X=881|Corner.Y=756|LineWidth=1|Color=16711680
|RECORD=41|OwnerIndex=860|IndexInSheet=14|OwnerPartId=-1|Location.X=870|Location.Y=801|Color=8388608|FontID=1|IsHidden=T|Text=Colorless|Name=Lens Color
|RECORD=41|OwnerIndex=860|IndexInSheet=15|OwnerPartId=-1|Location.X=870|Location.Y=801|Color=8388608|FontID=1|IsHidden=T|Text=1608|Name=Case Code (Metric)
|RECORD=41|OwnerIndex=860|IndexInSheet=16|OwnerPartId=-1|Location.X=870|Location.Y=801|Color=8388608|FontID=1|IsHidden=T|Text=Tape and Reel|Name=Packaging
|RECORD=41|OwnerIndex=860|IndexInSheet=17|OwnerPartId=-1|Location.X=870|Location.Y=801|Color=8388608|FontID=1|IsHidden=T|Text=0603|Name=Case/Package
|RECORD=41|OwnerIndex=860|IndexInSheet=18|OwnerPartId=-1|Location.X=870|Location.Y=801|Color=8388608|FontID=1|IsHidden=T|Text=1.6mm|Name=Depth
|RECORD=41|OwnerIndex=860|IndexInSheet=19|OwnerPartId=-1|Location.X=870|Location.Y=801|Color=8388608|FontID=1|IsHidden=T|Text=475nm|Name=Dominant Wavelength
|RECORD=41|OwnerIndex=860|IndexInSheet=20|OwnerPartId=-1|Location.X=870|Location.Y=801|Color=8388608|FontID=1|IsHidden=T|Text=Surface Mount|Name=Mount
|RECORD=41|OwnerIndex=860|IndexInSheet=21|OwnerPartId=-1|Location.X=870|Location.Y=801|Color=8388608|FontID=1|IsHidden=T|Text=20mA|Name=Forward Current
|RECORD=41|OwnerIndex=860|IndexInSheet=22|OwnerPartId=-1|Location.X=870|Location.Y=801|Color=8388608|FontID=1|IsHidden=T|Text=Lead Free|Name=Lead Free
|RECORD=41|OwnerIndex=860|IndexInSheet=23|OwnerPartId=-1|Location.X=870|Location.Y=801|Color=8388608|FontID=1|IsHidden=T|Text=468nm|Name=Wavelength
|RECORD=41|OwnerIndex=860|IndexInSheet=24|OwnerPartId=-1|Location.X=870|Location.Y=801|Color=8388608|FontID=1|IsHidden=T|Text=130°|Name=Viewing Angle
|RECORD=41|OwnerIndex=860|IndexInSheet=25|OwnerPartId=-1|Location.X=870|Location.Y=801|Color=8388608|FontID=1|IsHidden=T|Text=-20°C|Name=Min Operating Temperature
|RECORD=41|OwnerIndex=860|IndexInSheet=26|OwnerPartId=-1|Location.X=870|Location.Y=801|Color=8388608|FontID=1|IsHidden=T|Text=Clear|Name=Lens Transparency
|RECORD=41|OwnerIndex=860|IndexInSheet=27|OwnerPartId=-1|Location.X=870|Location.Y=801|Color=8388608|FontID=1|IsHidden=T|Text=76mW|Name=Power Dissipation
|RECORD=41|OwnerIndex=860|IndexInSheet=28|OwnerPartId=-1|Location.X=870|Location.Y=801|Color=8388608|FontID=1|IsHidden=T|Text=Blue|Name=Illumination Color
|RECORD=41|OwnerIndex=860|IndexInSheet=29|OwnerPartId=-1|Location.X=870|Location.Y=801|Color=8388608|FontID=1|IsHidden=T|Text=0.55mm|Name=Height
|RECORD=41|OwnerIndex=860|IndexInSheet=30|OwnerPartId=-1|Location.X=870|Location.Y=801|Color=8388608|FontID=1|IsHidden=T|Text=20mA|Name=Test Current
|RECORD=41|OwnerIndex=860|IndexInSheet=31|OwnerPartId=-1|Location.X=870|Location.Y=801|Color=8388608|FontID=1|IsHidden=T|Text=0603|Name=Case Code (Imperial)
|RECORD=41|OwnerIndex=860|IndexInSheet=32|OwnerPartId=-1|Location.X=870|Location.Y=801|Color=8388608|FontID=1|IsHidden=T|Text=180mcd|Name=Luminous Intensity
|RECORD=41|OwnerIndex=860|IndexInSheet=33|OwnerPartId=-1|Location.X=870|Location.Y=801|Color=8388608|FontID=1|IsHidden=T|Text=5V|Name=Reverse Voltage
|RECORD=41|OwnerIndex=860|IndexInSheet=34|OwnerPartId=-1|Location.X=870|Location.Y=801|Color=8388608|FontID=1|IsHidden=T|Text=80°C|Name=Max Operating Temperature
|RECORD=41|OwnerIndex=860|IndexInSheet=35|OwnerPartId=-1|Location.X=870|Location.Y=801|Color=8388608|FontID=1|IsHidden=T|Text=2|Name=Number of Pins
|RECORD=41|OwnerIndex=860|IndexInSheet=36|OwnerPartId=-1|Location.X=870|Location.Y=801|Color=8388608|FontID=1|IsHidden=T|Text=0.8mm|Name=Length
|RECORD=41|OwnerIndex=860|IndexInSheet=37|OwnerPartId=-1|Location.X=870|Location.Y=801|Color=8388608|FontID=1|IsHidden=T|Text=No|Name=Radiation Hardening
|RECORD=41|OwnerIndex=860|IndexInSheet=38|OwnerPartId=-1|Location.X=870|Location.Y=801|Color=8388608|FontID=1|IsHidden=T|Text=1|Name=Number of Elements
|RECORD=41|OwnerIndex=860|IndexInSheet=39|OwnerPartId=-1|Location.X=870|Location.Y=801|Color=8388608|FontID=1|IsHidden=T|Text=1|Name=Package Quantity
|RECORD=41|OwnerIndex=860|IndexInSheet=40|OwnerPartId=-1|Location.X=870|Location.Y=801|Color=8388608|FontID=1|IsHidden=T|Text=1|Name=Number of LEDs
|RECORD=41|OwnerIndex=860|IndexInSheet=41|OwnerPartId=-1|Location.X=870|Location.Y=801|Color=8388608|FontID=1|IsHidden=T|Text=Diffused|Name=Lens Style
|RECORD=41|OwnerIndex=860|IndexInSheet=42|OwnerPartId=-1|Location.X=870|Location.Y=801|Color=8388608|FontID=1|IsHidden=T|Text=3.8V|Name=Forward Voltage
|RECORD=41|OwnerIndex=860|IndexInSheet=43|OwnerPartId=-1|Location.X=870|Location.Y=801|Color=8388608|FontID=1|IsHidden=T|Text=0.8mm|Name=Width
|RECORD=41|OwnerIndex=860|IndexInSheet=44|OwnerPartId=-1|Location.X=870|Location.Y=801|Color=8388608|FontID=1|IsHidden=T|Text=75mW|Name=Max Power Dissipation
|RECORD=41|OwnerIndex=860|IndexInSheet=45|OwnerPartId=-1|Location.X=870|Location.Y=801|Color=8388608|FontID=1|IsHidden=T|Text=Blue|Name=Color
|RECORD=34|OwnerIndex=860|IndexInSheet=-1|OwnerPartId=-1|Location.X=904|Location.Y=773|Color=8388608|FontID=1|Text=D11|Name=Designator|ReadOnlyState=1
|RECORD=41|OwnerIndex=860|IndexInSheet=-1|OwnerPartId=1|Location.X=904|Location.Y=763|Color=8388608|FontID=1|Text=BLUE|Name=Comment
|RECORD=44|OwnerIndex=860
|RECORD=45|OwnerIndex=911|IndexInSheet=-1|UseComponentLibrary=T|ModelName=FP-LTST-C191TBKT-MFG|ModelType=PCBLIB|DatafileCount=1|ModelDatafileEntity0=FP-LTST-C191TBKT-MFG|ModelDatafileKind0=PCBLib|IsCurrent=T|DatalinksLocked=T|DatabaseDatalinksLocked=T
|RECORD=46|OwnerIndex=912
|RECORD=48|OwnerIndex=912
|RECORD=1|LibReference=RES-2|ComponentDescription=Chip Resistor, 4.7 KOhm, +/- 1%, 0.1 W, -55 to 155 degC, 0402 (1005 Metric), RoHS, Tape and Reel|PartCount=2|DisplayModeCount=1|IndexInSheet=53|OwnerPartId=-1|Location.X=364|Location.Y=425|Orientation=3|CurrentPartId=1|LibraryPath=*|SourceLibraryName=Altium Content Vault|TargetFileName=*|AreaColor=11599871|Color=128|PartIDLocked=T|DesignItemId=CMP-2002-01154-4|AllPinCount=2
|RECORD=2|OwnerIndex=915|OwnerPartId=1|FormalType=1|Electrical=4|PinConglomerate=35|PinLength=10|Location.X=364|Location.Y=405|Name=2|Designator=2|PinPropagationDelay=0.000000E+000
|RECORD=2|OwnerIndex=915|OwnerPartId=1|FormalType=1|Electrical=4|PinConglomerate=33|PinLength=10|Location.X=364|Location.Y=425|Name=1|Designator=1|PinPropagationDelay=0.000000E+000
|RECORD=6|OwnerIndex=915|IsNotAccesible=T|IndexInSheet=2|OwnerPartId=1|LineWidth=1|Color=16711680|LocationCount=10|X1=364|Y1=405|X2=364|Y2=409|X3=362|Y3=410|X4=366|Y4=412|X5=362|Y5=414|X6=366|Y6=416|X7=362|Y7=418|X8=366|Y8=420|X9=364|Y9=421|X10=364|Y10=425
|RECORD=41|OwnerIndex=915|IndexInSheet=3|OwnerPartId=-1|Location.X=361|Location.Y=437|Color=8388608|FontID=1|IsHidden=T|Text=0.35 mm|Name=Height
|RECORD=41|OwnerIndex=915|IndexInSheet=4|OwnerPartId=-1|Location.X=361|Location.Y=437|Color=8388608|FontID=1|IsHidden=T|Text=Surface Mount|Name=Mounting Technology
|RECORD=41|OwnerIndex=915|IndexInSheet=5|OwnerPartId=-1|Location.X=361|Location.Y=437|Color=8388608|FontID=1|IsHidden=T|Text=Yes|Name=REACH SVHC
|RECORD=41|OwnerIndex=915|IndexInSheet=6|OwnerPartId=-1|Location.X=361|Location.Y=437|Color=8388608|FontID=1|IsHidden=T|Text=4.7 KOhm|Name=Resistance
|RECORD=41|OwnerIndex=915|IndexInSheet=7|OwnerPartId=-1|Location.X=361|Location.Y=437|Color=8388608|FontID=1|IsHidden=T|Text=155 degC|Name=Max Operating Temperature
|RECORD=41|OwnerIndex=915|IndexInSheet=8|OwnerPartId=-1|Location.X=361|Location.Y=437|Color=8388608|FontID=1|IsHidden=T|Text=Manufacturer URL|Name=ComponentLink1Description
|RECORD=41|OwnerIndex=915|IndexInSheet=9|OwnerPartId=-1|Location.X=361|Location.Y=437|Color=8388608|FontID=1|IsHidden=T|Text=Datasheet|Name=ComponentLink2Description
|RECORD=41|OwnerIndex=915|IndexInSheet=10|OwnerPartId=-1|Location.X=361|Location.Y=437|Color=8388608|FontID=1|IsHidden=T|Text=2|Name=Pins
|RECORD=41|OwnerIndex=915|IndexInSheet=11|OwnerPartId=-1|Location.X=361|Location.Y=437|Color=8388608|FontID=1|IsHidden=T|Text=0402|Name=PackageReference
|RECORD=41|OwnerIndex=915|IndexInSheet=12|OwnerPartId=-1|Location.X=361|Location.Y=437|Color=8388608|FontID=1|IsHidden=T|Text=1%|Name=Tolerance
|RECORD=41|OwnerIndex=915|IndexInSheet=13|OwnerPartId=-1|Location.X=361|Location.Y=437|Color=8388608|FontID=1|IsHidden=T|Text=0402|Name=Case Code (Imperial)
|RECORD=41|OwnerIndex=915|IndexInSheet=14|OwnerPartId=-1|Location.X=361|Location.Y=437|Color=8388608|FontID=1|IsHidden=T|Text=1 mm|Name=Length
|RECORD=41|OwnerIndex=915|IndexInSheet=15|OwnerPartId=-1|Location.X=361|Location.Y=437|Color=8388608|FontID=1|IsHidden=T|Text=2-Pin Surface Mount Device, Body 1 x 0.5 mm|Name=PackageDescription
|RECORD=41|OwnerIndex=915|IndexInSheet=16|OwnerPartId=-1|Location.X=361|Location.Y=437|Color=8388608|FontID=1|IsHidden=T|Text=ERJ-2RKF4701X|Name=PartNumber
|RECORD=41|OwnerIndex=915|IndexInSheet=17|OwnerPartId=-1|Location.X=361|Location.Y=437|Color=8388608|FontID=1|IsHidden=T|Text=true|Name=RoHSCompliant
|RECORD=41|OwnerIndex=915|IndexInSheet=18|OwnerPartId=-1|Location.X=361|Location.Y=437|Color=8388608|FontID=1|IsHidden=T|Text=1|Name=Package Quantity
|RECORD=41|OwnerIndex=915|IndexInSheet=19|OwnerPartId=-1|Location.X=361|Location.Y=437|Color=8388608|FontID=1|IsHidden=T|Text=No|Name=Radiation Hardening
|RECORD=41|OwnerIndex=915|IndexInSheet=20|OwnerPartId=-1|Location.X=361|Location.Y=437|Color=8388608|FontID=1|IsHidden=T|Text=04/2015|Name=DatasheetVersion
|RECORD=41|OwnerIndex=915|IndexInSheet=21|OwnerPartId=-1|Location.X=361|Location.Y=437|Color=8388608|FontID=1|IsHidden=T|Text=0.5 mm|Name=Width
|RECORD=41|OwnerIndex=915|IndexInSheet=22|OwnerPartId=-1|Location.X=361|Location.Y=437|Color=8388608|FontID=1|IsHidden=T|Text=1005|Name=Case Code (Metric)
|RECORD=41|OwnerIndex=915|IndexInSheet=23|OwnerPartId=-1|Location.X=361|Location.Y=437|Color=8388608|FontID=1|IsHidden=T|Text=50 V|Name=Voltage Rating
|RECORD=41|OwnerIndex=915|IndexInSheet=24|OwnerPartId=-1|Location.X=361|Location.Y=437|Color=8388608|FontID=1|IsHidden=T|Text=0402|Name=Case\/Package
|RECORD=41|OwnerIndex=915|IndexInSheet=25|OwnerPartId=-1|Location.X=361|Location.Y=437|Color=8388608|FontID=1|IsHidden=T|Text=Surface Mount|Name=Mount
|RECORD=41|OwnerIndex=915|IndexInSheet=26|OwnerPartId=-1|Location.X=361|Location.Y=437|Color=8388608|FontID=5|IsHidden=T|Text=http://www.panasonic.com/|Name=ComponentLink1URL
|RECORD=41|OwnerIndex=915|IndexInSheet=27|OwnerPartId=-1|Location.X=361|Location.Y=437|Color=8388608|FontID=1|IsHidden=T|Text=-55 degC|Name=Min Operating Temperature
|RECORD=41|OwnerIndex=915|IndexInSheet=28|OwnerPartId=-1|Location.X=361|Location.Y=437|Color=8388608|FontID=1|IsHidden=T|Text=100 mW|Name=Power Rating
|RECORD=41|OwnerIndex=915|IndexInSheet=29|OwnerPartId=-1|Location.X=361|Location.Y=437|Color=8388608|FontID=1|IsHidden=T|Text=Cut Tape|Name=Packaging
|RECORD=41|OwnerIndex=915|IndexInSheet=30|OwnerPartId=-1|Location.X=361|Location.Y=437|Color=8388608|FontID=5|IsHidden=T|Text=http://industrial.panasonic.com/cdbs/www-data/pdf/RDA0000/AOA0000C86.pdf|Name=ComponentLink2URL
|RECORD=34|OwnerIndex=915|IndexInSheet=-1|OwnerPartId=-1|Location.X=367|Location.Y=416|Color=8388608|FontID=1|Text=R109|Name=Designator|ReadOnlyState=1
|RECORD=41|OwnerIndex=915|IndexInSheet=-1|OwnerPartId=-1|Location.X=367|Location.Y=406|Color=8388608|FontID=1|Text=4.7K_0402|Name=Comment
|RECORD=44|OwnerIndex=915
|RECORD=45|OwnerIndex=951|IndexInSheet=-1|Description=Chip Resistor, 2-Leads, Body 1.05x0.55mm, IPC High Density|UseComponentLibrary=T|ModelName=RESC1005X40X25LL05T05|ModelType=PCBLIB|DatafileCount=1|ModelDatafileEntity0=RESC1005X40X25LL05T05|ModelDatafileKind0=PCBLib|IsCurrent=T|DatalinksLocked=T|DatabaseDatalinksLocked=T
|RECORD=46|OwnerIndex=952
|RECORD=48|OwnerIndex=952
|RECORD=41|OwnerIndex=954|IndexInSheet=-1|OwnerPartId=-1|Color=8388608|FontID=1|IsHidden=T|Text=2D|Name=Available Preview Images
|RECORD=45|OwnerIndex=951|IndexInSheet=-1|Description=Chip Resistor, 2-Leads, Body 1.05x0.55mm, IPC Low Density|UseComponentLibrary=T|ModelName=RESC1005X40X25ML05T05|ModelType=PCBLIB|DatafileCount=1|ModelDatafileEntity0=RESC1005X40X25ML05T05|ModelDatafileKind0=PCBLib|DatalinksLocked=T|DatabaseDatalinksLocked=T
|RECORD=46|OwnerIndex=956
|RECORD=48|OwnerIndex=956
|RECORD=41|OwnerIndex=958|IndexInSheet=-1|OwnerPartId=-1|Color=8388608|FontID=1|IsHidden=T|Text=2D|Name=Available Preview Images
|RECORD=45|OwnerIndex=951|IndexInSheet=-1|Description=Chip Resistor, 2-Leads, Body 1.05x0.55mm, IPC Medium Density|UseComponentLibrary=T|ModelName=RESC1005X40X25NL05T05|ModelType=PCBLIB|DatafileCount=1|ModelDatafileEntity0=RESC1005X40X25NL05T05|ModelDatafileKind0=PCBLib|DatalinksLocked=T|DatabaseDatalinksLocked=T
|RECORD=46|OwnerIndex=960
|RECORD=48|OwnerIndex=960
|RECORD=41|OwnerIndex=962|IndexInSheet=-1|OwnerPartId=-1|Color=8388608|FontID=1|IsHidden=T|Text=2D|Name=Available Preview Images
|RECORD=17|IndexInSheet=54|OwnerPartId=-1|ShowNetName=T|Location.X=364|Location.Y=455|Orientation=1|Color=128|FontID=1|Text=+3.3V
|RECORD=27|IndexInSheet=55|OwnerPartId=-1|LineWidth=1|Color=8388608|LocationCount=2|X1=581|Y1=739|X2=581|Y2=729
|RECORD=27|IndexInSheet=56|OwnerPartId=-1|LineWidth=1|Color=8388608|LocationCount=2|X1=681|Y1=739|X2=681|Y2=729
|RECORD=27|IndexInSheet=57|OwnerPartId=-1|LineWidth=1|Color=8388608|LocationCount=2|X1=781|Y1=739|X2=781|Y2=729
|RECORD=27|IndexInSheet=58|OwnerPartId=-1|LineWidth=1|Color=8388608|LocationCount=2|X1=881|Y1=739|X2=881|Y2=729
|RECORD=27|IndexInSheet=59|OwnerPartId=-1|LineWidth=1|Color=8388608|LocationCount=3|X1=581|Y1=689|X2=581|Y2=669|X3=571|Y3=669
|RECORD=27|IndexInSheet=60|OwnerPartId=-1|LineWidth=1|Color=8388608|LocationCount=3|X1=681|Y1=689|X2=681|Y2=669|X3=671|Y3=669
|RECORD=27|IndexInSheet=61|OwnerPartId=-1|LineWidth=1|Color=8388608|LocationCount=3|X1=781|Y1=689|X2=781|Y2=669|X3=771|Y3=669
|RECORD=27|IndexInSheet=62|OwnerPartId=-1|LineWidth=1|Color=8388608|LocationCount=3|X1=881|Y1=689|X2=881|Y2=669|X3=871|Y3=669
|RECORD=27|IndexInSheet=63|OwnerPartId=-1|LineWidth=1|Color=8388608|LocationCount=4|X1=1114|Y1=505|X2=834|Y2=505|X3=834|Y3=445|X4=794|Y4=445
|RECORD=27|IndexInSheet=64|OwnerPartId=-1|LineWidth=1|Color=8388608|LocationCount=4|X1=794|Y1=435|X2=844|Y2=435|X3=844|Y3=495|X4=1114|Y4=495
|RECORD=27|IndexInSheet=65|OwnerPartId=-1|LineWidth=1|Color=8388608|LocationCount=4|X1=1114|Y1=485|X2=854|Y2=485|X3=854|Y3=425|X4=794|Y4=425
|RECORD=27|IndexInSheet=66|OwnerPartId=-1|LineWidth=1|Color=8388608|LocationCount=4|X1=794|Y1=405|X2=884|Y2=405|X3=884|Y3=445|X4=1114|Y4=445
|RECORD=27|IndexInSheet=67|OwnerPartId=-1|LineWidth=1|Color=8388608|LocationCount=4|X1=1114|Y1=435|X2=894|Y2=435|X3=894|Y3=395|X4=794|Y4=395
|RECORD=27|IndexInSheet=68|OwnerPartId=-1|LineWidth=1|Color=8388608|LocationCount=4|X1=794|Y1=385|X2=904|Y2=385|X3=904|Y3=425|X4=1114|Y4=425
|RECORD=27|IndexInSheet=69|OwnerPartId=-1|LineWidth=1|Color=8388608|LocationCount=4|X1=1114|Y1=385|X2=944|Y2=385|X3=944|Y3=365|X4=794|Y4=365
|RECORD=27|IndexInSheet=70|OwnerPartId=-1|LineWidth=1|Color=8388608|LocationCount=4|X1=794|Y1=355|X2=954|Y2=355|X3=954|Y3=375|X4=1114|Y4=375
|RECORD=27|IndexInSheet=71|OwnerPartId=-1|LineWidth=1|Color=8388608|LocationCount=4|X1=1114|Y1=365|X2=964|Y2=365|X3=964|Y3=345|X4=794|Y4=345
|RECORD=27|IndexInSheet=72|OwnerPartId=-1|LineWidth=1|Color=8388608|LocationCount=2|X1=794|Y1=325|X2=1114|Y2=325
|RECORD=27|IndexInSheet=73|OwnerPartId=-1|LineWidth=1|Color=8388608|LocationCount=2|X1=1114|Y1=315|X2=794|Y2=315
|RECORD=27|IndexInSheet=74|OwnerPartId=-1|LineWidth=1|Color=8388608|LocationCount=2|X1=794|Y1=305|X2=1114|Y2=305
|RECORD=27|IndexInSheet=75|OwnerPartId=-1|LineWidth=1|Color=8388608|LocationCount=4|X1=1114|Y1=255|X2=964|Y2=255|X3=964|Y3=285|X4=794|Y4=285
|RECORD=27|IndexInSheet=76|OwnerPartId=-1|LineWidth=1|Color=8388608|LocationCount=4|X1=794|Y1=275|X2=954|Y2=275|X3=954|Y3=245|X4=1114|Y4=245
|RECORD=27|IndexInSheet=77|OwnerPartId=-1|LineWidth=1|Color=8388608|LocationCount=4|X1=1114|Y1=235|X2=944|Y2=235|X3=944|Y3=265|X4=794|Y4=265
|RECORD=27|IndexInSheet=78|OwnerPartId=-1|LineWidth=1|Color=8388608|LocationCount=4|X1=794|Y1=245|X2=904|Y2=245|X3=904|Y3=185|X4=1114|Y4=185
|RECORD=27|IndexInSheet=79|OwnerPartId=-1|LineWidth=1|Color=8388608|LocationCount=4|X1=1114|Y1=175|X2=894|Y2=175|X3=894|Y3=235|X4=794|Y4=235
|RECORD=27|IndexInSheet=80|OwnerPartId=-1|LineWidth=1|Color=8388608|LocationCount=4|X1=794|Y1=225|X2=884|Y2=225|X3=884|Y3=165|X4=1114|Y4=165
|RECORD=27|IndexInSheet=81|OwnerPartId=-1|LineWidth=1|Color=8388608|LocationCount=2|X1=1214|Y1=255|X2=1244|Y2=255
|RECORD=27|IndexInSheet=82|OwnerPartId=-1|LineWidth=1|Color=8388608|LocationCount=2|X1=1214|Y1=325|X2=1244|Y2=325
|RECORD=27|IndexInSheet=83|OwnerPartId=-1|LineWidth=1|Color=8388608|LocationCount=2|X1=1214|Y1=385|X2=1244|Y2=385
|RECORD=27|IndexInSheet=84|OwnerPartId=-1|LineWidth=1|Color=8388608|LocationCount=2|X1=1214|Y1=445|X2=1244|Y2=445
|RECORD=27|IndexInSheet=85|OwnerPartId=-1|LineWidth=1|Color=8388608|LocationCount=2|X1=1214|Y1=505|X2=1244|Y2=505
|RECORD=27|IndexInSheet=86|OwnerPartId=-1|LineWidth=1|Color=8388608|LocationCount=2|X1=534|Y1=175|X2=534|Y2=155
|RECORD=27|IndexInSheet=87|OwnerPartId=-1|LineWidth=1|Color=8388608|LocationCount=2|X1=444|Y1=185|X2=444|Y2=155
|RECORD=27|IndexInSheet=88|OwnerPartId=-1|LineWidth=1|Color=8388608|LocationCount=3|X1=644|Y1=225|X2=614|Y2=225|X3=614|Y3=155
|RECORD=27|IndexInSheet=89|OwnerPartId=-1|LineWidth=1|Color=8388608|LocationCount=3|X1=644|Y1=235|X2=614|Y2=235|X3=614|Y3=225
|RECORD=27|IndexInSheet=90|OwnerPartId=-1|LineWidth=1|Color=8388608|LocationCount=3|X1=644|Y1=245|X2=614|Y2=245|X3=614|Y3=235
|RECORD=27|IndexInSheet=91|OwnerPartId=-1|LineWidth=1|Color=8388608|LocationCount=3|X1=644|Y1=255|X2=614|Y2=255|X3=614|Y3=245
|RECORD=27|IndexInSheet=92|OwnerPartId=-1|LineWidth=1|Color=8388608|LocationCount=3|X1=644|Y1=265|X2=614|Y2=265|X3=614|Y3=255
|RECORD=27|IndexInSheet=93|OwnerPartId=-1|LineWidth=1|Color=8388608|LocationCount=2|X1=364|Y1=165|X2=364|Y2=155
|RECORD=27|IndexInSheet=94|OwnerPartId=-1|LineWidth=1|Color=8388608|LocationCount=2|X1=464|Y1=295|X2=464|Y2=465
|RECORD=27|IndexInSheet=95|OwnerPartId=-1|LineWidth=1|Color=8388608|LocationCount=2|X1=644|Y1=445|X2=584|Y2=445
|RECORD=27|IndexInSheet=96|OwnerPartId=-1|LineWidth=1|Color=8388608|LocationCount=2|X1=644|Y1=435|X2=579|Y2=435
|RECORD=27|IndexInSheet=97|OwnerPartId=-1|LineWidth=1|Color=8388608|LocationCount=3|X1=644|Y1=365|X2=564|Y2=365|X3=564|Y3=215
|RECORD=27|IndexInSheet=98|OwnerPartId=-1|LineWidth=1|Color=8388608|LocationCount=2|X1=564|Y1=175|X2=564|Y2=155
|RECORD=27|IndexInSheet=99|OwnerPartId=-1|LineWidth=1|Color=8388608|LocationCount=2|X1=681|Y1=799|X2=681|Y2=829
|RECORD=27|IndexInSheet=100|OwnerPartId=-1|LineWidth=1|Color=8388608|LocationCount=2|X1=781|Y1=799|X2=781|Y2=829
|RECORD=27|IndexInSheet=101|OwnerPartId=-1|LineWidth=1|Color=8388608|LocationCount=2|X1=881|Y1=799|X2=881|Y2=829
|RECORD=27|IndexInSheet=102|OwnerPartId=-1|LineWidth=1|Color=8388608|LocationCount=2|X1=581|Y1=824|X2=581|Y2=799
|RECORD=27|IndexInSheet=103|OwnerPartId=-1|LineWidth=1|Color=8388608|LocationCount=2|X1=364|Y1=385|X2=364|Y2=395
|RECORD=27|IndexInSheet=104|OwnerPartId=-1|LineWidth=1|Color=8388608|LocationCount=2|X1=364|Y1=435|X2=364|Y2=455
|RECORD=27|IndexInSheet=105|OwnerPartId=-1|LineWidth=1|Color=8388608|LocationCount=2|X1=534|Y1=205|X2=534|Y2=295
|RECORD=1|LibReference=RES-2|ComponentDescription=Chip Resistor, 4.7 KOhm, +/- 1%, 0.1 W, -55 to 155 degC, 0402 (1005 Metric), RoHS, Tape and Reel|PartCount=2|DisplayModeCount=1|IndexInSheet=106|OwnerPartId=-1|Location.X=494|Location.Y=240|Orientation=3|CurrentPartId=1|LibraryPath=*|SourceLibraryName=Altium Content Vault|TargetFileName=*|AreaColor=11599871|Color=128|PartIDLocked=T|DesignItemId=CMP-2002-01154-4|AllPinCount=2|ComponentKindVersion2=5
|RECORD=2|OwnerIndex=1016|OwnerPartId=1|FormalType=1|Electrical=4|PinConglomerate=35|PinLength=10|Location.X=494|Location.Y=220|Name=2|Designator=2|PinPropagationDelay=0.000000E+000
|RECORD=2|OwnerIndex=1016|OwnerPartId=1|FormalType=1|Electrical=4|PinConglomerate=33|PinLength=10|Location.X=494|Location.Y=240|Name=1|Designator=1|PinPropagationDelay=0.000000E+000
|RECORD=6|OwnerIndex=1016|IsNotAccesible=T|IndexInSheet=2|OwnerPartId=1|LineWidth=1|Color=16711680|LocationCount=10|X1=494|Y1=220|X2=494|Y2=224|X3=492|Y3=225|X4=496|Y4=227|X5=492|Y5=229|X6=496|Y6=231|X7=492|Y7=233|X8=496|Y8=235|X9=494|Y9=236|X10=494|Y10=240
|RECORD=41|OwnerIndex=1016|IndexInSheet=3|OwnerPartId=-1|Location.X=491|Location.Y=252|Color=8388608|FontID=1|IsHidden=T|Text=0.35 mm|Name=Height
|RECORD=41|OwnerIndex=1016|IndexInSheet=4|OwnerPartId=-1|Location.X=491|Location.Y=252|Color=8388608|FontID=1|IsHidden=T|Text=Surface Mount|Name=Mounting Technology
|RECORD=41|OwnerIndex=1016|IndexInSheet=5|OwnerPartId=-1|Location.X=491|Location.Y=252|Color=8388608|FontID=1|IsHidden=T|Text=Yes|Name=REACH SVHC
|RECORD=41|OwnerIndex=1016|IndexInSheet=6|OwnerPartId=-1|Location.X=491|Location.Y=252|Color=8388608|FontID=1|IsHidden=T|Text=4.7 KOhm|Name=Resistance
|RECORD=41|OwnerIndex=1016|IndexInSheet=7|OwnerPartId=-1|Location.X=491|Location.Y=252|Color=8388608|FontID=1|IsHidden=T|Text=155 degC|Name=Max Operating Temperature
|RECORD=41|OwnerIndex=1016|IndexInSheet=8|OwnerPartId=-1|Location.X=491|Location.Y=252|Color=8388608|FontID=1|IsHidden=T|Text=Manufacturer URL|Name=ComponentLink1Description
|RECORD=41|OwnerIndex=1016|IndexInSheet=9|OwnerPartId=-1|Location.X=491|Location.Y=252|Color=8388608|FontID=1|IsHidden=T|Text=Datasheet|Name=ComponentLink2Description
|RECORD=41|OwnerIndex=1016|IndexInSheet=10|OwnerPartId=-1|Location.X=491|Location.Y=252|Color=8388608|FontID=1|IsHidden=T|Text=2|Name=Pins
|RECORD=41|OwnerIndex=1016|IndexInSheet=11|OwnerPartId=-1|Location.X=491|Location.Y=252|Color=8388608|FontID=1|IsHidden=T|Text=0402|Name=PackageReference
|RECORD=41|OwnerIndex=1016|IndexInSheet=12|OwnerPartId=-1|Location.X=491|Location.Y=252|Color=8388608|FontID=1|IsHidden=T|Text=1%|Name=Tolerance
|RECORD=41|OwnerIndex=1016|IndexInSheet=13|OwnerPartId=-1|Location.X=491|Location.Y=252|Color=8388608|FontID=1|IsHidden=T|Text=0402|Name=Case Code (Imperial)
|RECORD=41|OwnerIndex=1016|IndexInSheet=14|OwnerPartId=-1|Location.X=491|Location.Y=252|Color=8388608|FontID=1|IsHidden=T|Text=1 mm|Name=Length
|RECORD=41|OwnerIndex=1016|IndexInSheet=15|OwnerPartId=-1|Location.X=491|Location.Y=252|Color=8388608|FontID=1|IsHidden=T|Text=2-Pin Surface Mount Device, Body 1 x 0.5 mm|Name=PackageDescription
|RECORD=41|OwnerIndex=1016|IndexInSheet=16|OwnerPartId=-1|Location.X=491|Location.Y=252|Color=8388608|FontID=1|IsHidden=T|Text=ERJ-2RKF4701X|Name=PartNumber
|RECORD=41|OwnerIndex=1016|IndexInSheet=17|OwnerPartId=-1|Location.X=491|Location.Y=252|Color=8388608|FontID=1|IsHidden=T|Text=true|Name=RoHSCompliant
|RECORD=41|OwnerIndex=1016|IndexInSheet=18|OwnerPartId=-1|Location.X=491|Location.Y=252|Color=8388608|FontID=1|IsHidden=T|Text=1|Name=Package Quantity
|RECORD=41|OwnerIndex=1016|IndexInSheet=19|OwnerPartId=-1|Location.X=491|Location.Y=252|Color=8388608|FontID=1|IsHidden=T|Text=No|Name=Radiation Hardening
|RECORD=41|OwnerIndex=1016|IndexInSheet=20|OwnerPartId=-1|Location.X=491|Location.Y=252|Color=8388608|FontID=1|IsHidden=T|Text=04/2015|Name=DatasheetVersion
|RECORD=41|OwnerIndex=1016|IndexInSheet=21|OwnerPartId=-1|Location.X=491|Location.Y=252|Color=8388608|FontID=1|IsHidden=T|Text=0.5 mm|Name=Width
|RECORD=41|OwnerIndex=1016|IndexInSheet=22|OwnerPartId=-1|Location.X=491|Location.Y=252|Color=8388608|FontID=1|IsHidden=T|Text=1005|Name=Case Code (Metric)
|RECORD=41|OwnerIndex=1016|IndexInSheet=23|OwnerPartId=-1|Location.X=491|Location.Y=252|Color=8388608|FontID=1|IsHidden=T|Text=50 V|Name=Voltage Rating
|RECORD=41|OwnerIndex=1016|IndexInSheet=24|OwnerPartId=-1|Location.X=491|Location.Y=252|Color=8388608|FontID=1|IsHidden=T|Text=0402|Name=Case\/Package
|RECORD=41|OwnerIndex=1016|IndexInSheet=25|OwnerPartId=-1|Location.X=491|Location.Y=252|Color=8388608|FontID=1|IsHidden=T|Text=Surface Mount|Name=Mount
|RECORD=41|OwnerIndex=1016|IndexInSheet=26|OwnerPartId=-1|Location.X=491|Location.Y=252|Color=8388608|FontID=5|IsHidden=T|Text=http://www.panasonic.com/|Name=ComponentLink1URL
|RECORD=41|OwnerIndex=1016|IndexInSheet=27|OwnerPartId=-1|Location.X=491|Location.Y=252|Color=8388608|FontID=1|IsHidden=T|Text=-55 degC|Name=Min Operating Temperature
|RECORD=41|OwnerIndex=1016|IndexInSheet=28|OwnerPartId=-1|Location.X=491|Location.Y=252|Color=8388608|FontID=1|IsHidden=T|Text=100 mW|Name=Power Rating
|RECORD=41|OwnerIndex=1016|IndexInSheet=29|OwnerPartId=-1|Location.X=491|Location.Y=252|Color=8388608|FontID=1|IsHidden=T|Text=Cut Tape|Name=Packaging
|RECORD=41|OwnerIndex=1016|IndexInSheet=30|OwnerPartId=-1|Location.X=491|Location.Y=252|Color=8388608|FontID=5|IsHidden=T|Text=http://industrial.panasonic.com/cdbs/www-data/pdf/RDA0000/AOA0000C86.pdf|Name=ComponentLink2URL
|RECORD=34|OwnerIndex=1016|IndexInSheet=-1|OwnerPartId=-1|Location.X=489|Location.Y=215|Orientation=1|Color=8388608|FontID=2|Text=R110|Name=Designator|ReadOnlyState=1
|RECORD=41|OwnerIndex=1016|IndexInSheet=-1|OwnerPartId=-1|Location.X=509|Location.Y=190|Orientation=1|Color=8388608|FontID=2|Text=DNI_4.7K_0402|Name=Comment
|RECORD=44|OwnerIndex=1016
|RECORD=45|OwnerIndex=1052|IndexInSheet=-1|Description=Chip Resistor, 2-Leads, Body 1.05x0.55mm, IPC High Density|UseComponentLibrary=T|ModelName=RESC1005X40X25LL05T05|ModelType=PCBLIB|DatafileCount=1|ModelDatafileEntity0=RESC1005X40X25LL05T05|ModelDatafileKind0=PCBLib|IsCurrent=T|DatalinksLocked=T|DatabaseDatalinksLocked=T
|RECORD=46|OwnerIndex=1053
|RECORD=48|OwnerIndex=1053
|RECORD=41|OwnerIndex=1055|IndexInSheet=-1|OwnerPartId=-1|Color=8388608|FontID=1|IsHidden=T|Text=2D|Name=Available Preview Images
|RECORD=45|OwnerIndex=1052|IndexInSheet=-1|Description=Chip Resistor, 2-Leads, Body 1.05x0.55mm, IPC Low Density|UseComponentLibrary=T|ModelName=RESC1005X40X25ML05T05|ModelType=PCBLIB|DatafileCount=1|ModelDatafileEntity0=RESC1005X40X25ML05T05|ModelDatafileKind0=PCBLib|DatalinksLocked=T|DatabaseDatalinksLocked=T
|RECORD=46|OwnerIndex=1057
|RECORD=48|OwnerIndex=1057
|RECORD=41|OwnerIndex=1059|IndexInSheet=-1|OwnerPartId=-1|Color=8388608|FontID=1|IsHidden=T|Text=2D|Name=Available Preview Images
|RECORD=45|OwnerIndex=1052|IndexInSheet=-1|Description=Chip Resistor, 2-Leads, Body 1.05x0.55mm, IPC Medium Density|UseComponentLibrary=T|ModelName=RESC1005X40X25NL05T05|ModelType=PCBLIB|DatafileCount=1|ModelDatafileEntity0=RESC1005X40X25NL05T05|ModelDatafileKind0=PCBLib|DatalinksLocked=T|DatabaseDatalinksLocked=T
|RECORD=46|OwnerIndex=1061
|RECORD=48|OwnerIndex=1061
|RECORD=41|OwnerIndex=1063|IndexInSheet=-1|OwnerPartId=-1|Color=8388608|FontID=1|IsHidden=T|Text=2D|Name=Available Preview Images
|RECORD=17|IndexInSheet=107|OwnerPartId=-1|Style=4|ShowNetName=T|Location.X=494|Location.Y=150|Orientation=3|Color=128|FontID=1|Text=GND
|RECORD=27|IndexInSheet=108|OwnerPartId=-1|LineWidth=1|Color=8388608|LocationCount=2|X1=494|Y1=210|X2=494|Y2=150
|RECORD=1|LibReference=RES-2|ComponentDescription=Chip Resistor, 4.7 KOhm, +/- 1%, 0.1 W, -55 to 155 degC, 0402 (1005 Metric), RoHS, Tape and Reel|PartCount=2|DisplayModeCount=1|IndexInSheet=109|OwnerPartId=-1|Location.X=494|Location.Y=470|Orientation=3|CurrentPartId=1|LibraryPath=*|SourceLibraryName=Altium Content Vault|TargetFileName=*|AreaColor=11599871|Color=128|PartIDLocked=T|DesignItemId=CMP-2002-01154-4|AllPinCount=2
|RECORD=2|OwnerIndex=1067|OwnerPartId=1|FormalType=1|Electrical=4|PinConglomerate=35|PinLength=10|Location.X=494|Location.Y=450|Name=2|Designator=2|PinPropagationDelay=0.000000E+000
|RECORD=2|OwnerIndex=1067|OwnerPartId=1|FormalType=1|Electrical=4|PinConglomerate=33|PinLength=10|Location.X=494|Location.Y=470|Name=1|Designator=1|PinPropagationDelay=0.000000E+000
|RECORD=6|OwnerIndex=1067|IsNotAccesible=T|IndexInSheet=2|OwnerPartId=1|LineWidth=1|Color=16711680|LocationCount=10|X1=494|Y1=450|X2=494|Y2=454|X3=492|Y3=455|X4=496|Y4=457|X5=492|Y5=459|X6=496|Y6=461|X7=492|Y7=463|X8=496|Y8=465|X9=494|Y9=466|X10=494|Y10=470
|RECORD=41|OwnerIndex=1067|IndexInSheet=3|OwnerPartId=-1|Location.X=491|Location.Y=482|Color=8388608|FontID=1|IsHidden=T|Text=0.35 mm|Name=Height
|RECORD=41|OwnerIndex=1067|IndexInSheet=4|OwnerPartId=-1|Location.X=491|Location.Y=482|Color=8388608|FontID=1|IsHidden=T|Text=Surface Mount|Name=Mounting Technology
|RECORD=41|OwnerIndex=1067|IndexInSheet=5|OwnerPartId=-1|Location.X=491|Location.Y=482|Color=8388608|FontID=1|IsHidden=T|Text=Yes|Name=REACH SVHC
|RECORD=41|OwnerIndex=1067|IndexInSheet=6|OwnerPartId=-1|Location.X=491|Location.Y=482|Color=8388608|FontID=1|IsHidden=T|Text=4.7 KOhm|Name=Resistance
|RECORD=41|OwnerIndex=1067|IndexInSheet=7|OwnerPartId=-1|Location.X=491|Location.Y=482|Color=8388608|FontID=1|IsHidden=T|Text=155 degC|Name=Max Operating Temperature
|RECORD=41|OwnerIndex=1067|IndexInSheet=8|OwnerPartId=-1|Location.X=491|Location.Y=482|Color=8388608|FontID=1|IsHidden=T|Text=Manufacturer URL|Name=ComponentLink1Description
|RECORD=41|OwnerIndex=1067|IndexInSheet=9|OwnerPartId=-1|Location.X=491|Location.Y=482|Color=8388608|FontID=1|IsHidden=T|Text=Datasheet|Name=ComponentLink2Description
|RECORD=41|OwnerIndex=1067|IndexInSheet=10|OwnerPartId=-1|Location.X=491|Location.Y=482|Color=8388608|FontID=1|IsHidden=T|Text=2|Name=Pins
|RECORD=41|OwnerIndex=1067|IndexInSheet=11|OwnerPartId=-1|Location.X=491|Location.Y=482|Color=8388608|FontID=1|IsHidden=T|Text=0402|Name=PackageReference
|RECORD=41|OwnerIndex=1067|IndexInSheet=12|OwnerPartId=-1|Location.X=491|Location.Y=482|Color=8388608|FontID=1|IsHidden=T|Text=1%|Name=Tolerance
|RECORD=41|OwnerIndex=1067|IndexInSheet=13|OwnerPartId=-1|Location.X=491|Location.Y=482|Color=8388608|FontID=1|IsHidden=T|Text=0402|Name=Case Code (Imperial)
|RECORD=41|OwnerIndex=1067|IndexInSheet=14|OwnerPartId=-1|Location.X=491|Location.Y=482|Color=8388608|FontID=1|IsHidden=T|Text=1 mm|Name=Length
|RECORD=41|OwnerIndex=1067|IndexInSheet=15|OwnerPartId=-1|Location.X=491|Location.Y=482|Color=8388608|FontID=1|IsHidden=T|Text=2-Pin Surface Mount Device, Body 1 x 0.5 mm|Name=PackageDescription
|RECORD=41|OwnerIndex=1067|IndexInSheet=16|OwnerPartId=-1|Location.X=491|Location.Y=482|Color=8388608|FontID=1|IsHidden=T|Text=ERJ-2RKF4701X|Name=PartNumber
|RECORD=41|OwnerIndex=1067|IndexInSheet=17|OwnerPartId=-1|Location.X=491|Location.Y=482|Color=8388608|FontID=1|IsHidden=T|Text=true|Name=RoHSCompliant
|RECORD=41|OwnerIndex=1067|IndexInSheet=18|OwnerPartId=-1|Location.X=491|Location.Y=482|Color=8388608|FontID=1|IsHidden=T|Text=1|Name=Package Quantity
|RECORD=41|OwnerIndex=1067|IndexInSheet=19|OwnerPartId=-1|Location.X=491|Location.Y=482|Color=8388608|FontID=1|IsHidden=T|Text=No|Name=Radiation Hardening
|RECORD=41|OwnerIndex=1067|IndexInSheet=20|OwnerPartId=-1|Location.X=491|Location.Y=482|Color=8388608|FontID=1|IsHidden=T|Text=04/2015|Name=DatasheetVersion
|RECORD=41|OwnerIndex=1067|IndexInSheet=21|OwnerPartId=-1|Location.X=491|Location.Y=482|Color=8388608|FontID=1|IsHidden=T|Text=0.5 mm|Name=Width
|RECORD=41|OwnerIndex=1067|IndexInSheet=22|OwnerPartId=-1|Location.X=491|Location.Y=482|Color=8388608|FontID=1|IsHidden=T|Text=1005|Name=Case Code (Metric)
|RECORD=41|OwnerIndex=1067|IndexInSheet=23|OwnerPartId=-1|Location.X=491|Location.Y=482|Color=8388608|FontID=1|IsHidden=T|Text=50 V|Name=Voltage Rating
|RECORD=41|OwnerIndex=1067|IndexInSheet=24|OwnerPartId=-1|Location.X=491|Location.Y=482|Color=8388608|FontID=1|IsHidden=T|Text=0402|Name=Case\/Package
|RECORD=41|OwnerIndex=1067|IndexInSheet=25|OwnerPartId=-1|Location.X=491|Location.Y=482|Color=8388608|FontID=1|IsHidden=T|Text=Surface Mount|Name=Mount
|RECORD=41|OwnerIndex=1067|IndexInSheet=26|OwnerPartId=-1|Location.X=491|Location.Y=482|Color=8388608|FontID=5|IsHidden=T|Text=http://www.panasonic.com/|Name=ComponentLink1URL
|RECORD=41|OwnerIndex=1067|IndexInSheet=27|OwnerPartId=-1|Location.X=491|Location.Y=482|Color=8388608|FontID=1|IsHidden=T|Text=-55 degC|Name=Min Operating Temperature
|RECORD=41|OwnerIndex=1067|IndexInSheet=28|OwnerPartId=-1|Location.X=491|Location.Y=482|Color=8388608|FontID=1|IsHidden=T|Text=100 mW|Name=Power Rating
|RECORD=41|OwnerIndex=1067|IndexInSheet=29|OwnerPartId=-1|Location.X=491|Location.Y=482|Color=8388608|FontID=1|IsHidden=T|Text=Cut Tape|Name=Packaging
|RECORD=41|OwnerIndex=1067|IndexInSheet=30|OwnerPartId=-1|Location.X=491|Location.Y=482|Color=8388608|FontID=5|IsHidden=T|Text=http://industrial.panasonic.com/cdbs/www-data/pdf/RDA0000/AOA0000C86.pdf|Name=ComponentLink2URL
|RECORD=34|OwnerIndex=1067|IndexInSheet=-1|OwnerPartId=-1|Location.X=497|Location.Y=461|Color=8388608|FontID=1|Text=R108|Name=Designator|ReadOnlyState=1
|RECORD=41|OwnerIndex=1067|IndexInSheet=-1|OwnerPartId=-1|Location.X=497|Location.Y=451|Color=8388608|FontID=1|Text=4.7K_0402|Name=Comment
|RECORD=44|OwnerIndex=1067
|RECORD=45|OwnerIndex=1103|IndexInSheet=-1|Description=Chip Resistor, 2-Leads, Body 1.05x0.55mm, IPC High Density|UseComponentLibrary=T|ModelName=RESC1005X40X25LL05T05|ModelType=PCBLIB|DatafileCount=1|ModelDatafileEntity0=RESC1005X40X25LL05T05|ModelDatafileKind0=PCBLib|IsCurrent=T|DatalinksLocked=T|DatabaseDatalinksLocked=T
|RECORD=46|OwnerIndex=1104
|RECORD=48|OwnerIndex=1104
|RECORD=41|OwnerIndex=1106|IndexInSheet=-1|OwnerPartId=-1|Color=8388608|FontID=1|IsHidden=T|Text=2D|Name=Available Preview Images
|RECORD=45|OwnerIndex=1103|IndexInSheet=-1|Description=Chip Resistor, 2-Leads, Body 1.05x0.55mm, IPC Low Density|UseComponentLibrary=T|ModelName=RESC1005X40X25ML05T05|ModelType=PCBLIB|DatafileCount=1|ModelDatafileEntity0=RESC1005X40X25ML05T05|ModelDatafileKind0=PCBLib|DatalinksLocked=T|DatabaseDatalinksLocked=T
|RECORD=46|OwnerIndex=1108
|RECORD=48|OwnerIndex=1108
|RECORD=41|OwnerIndex=1110|IndexInSheet=-1|OwnerPartId=-1|Color=8388608|FontID=1|IsHidden=T|Text=2D|Name=Available Preview Images
|RECORD=45|OwnerIndex=1103|IndexInSheet=-1|Description=Chip Resistor, 2-Leads, Body 1.05x0.55mm, IPC Medium Density|UseComponentLibrary=T|ModelName=RESC1005X40X25NL05T05|ModelType=PCBLIB|DatafileCount=1|ModelDatafileEntity0=RESC1005X40X25NL05T05|ModelDatafileKind0=PCBLib|DatalinksLocked=T|DatabaseDatalinksLocked=T
|RECORD=46|OwnerIndex=1112
|RECORD=48|OwnerIndex=1112
|RECORD=41|OwnerIndex=1114|IndexInSheet=-1|OwnerPartId=-1|Color=8388608|FontID=1|IsHidden=T|Text=2D|Name=Available Preview Images
|RECORD=27|IndexInSheet=110|OwnerPartId=-1|LineWidth=1|Color=8388608|LocationCount=2|X1=494|Y1=480|X2=494|Y2=490
|RECORD=27|IndexInSheet=111|OwnerPartId=-1|LineWidth=1|Color=8388608|LocationCount=2|X1=644|Y1=415|X2=494|Y2=415
|RECORD=27|IndexInSheet=112|OwnerPartId=-1|LineWidth=1|Color=8388608|LocationCount=3|X1=364|Y1=235|X2=364|Y2=385|X3=644|Y3=385
|RECORD=41|IndexInSheet=113|OwnerPartId=-1|Color=8388608|FontID=1|IsHidden=T|Text=*|Name=CurrentTime|ReadOnlyState=1
|RECORD=41|IndexInSheet=114|OwnerPartId=-1|Color=8388608|FontID=1|IsHidden=T|Text=*|Name=CurrentDate|ReadOnlyState=1
|RECORD=41|IndexInSheet=115|OwnerPartId=-1|Color=8388608|FontID=1|IsHidden=T|Text=*|Name=Time|ReadOnlyState=1
|RECORD=41|IndexInSheet=116|OwnerPartId=-1|Color=8388608|FontID=1|IsHidden=T|Text=*|Name=Date|ReadOnlyState=1
|RECORD=41|IndexInSheet=117|OwnerPartId=-1|Color=8388608|FontID=1|IsHidden=T|Text=*|Name=DocumentFullPathAndName|ReadOnlyState=1
|RECORD=41|IndexInSheet=118|OwnerPartId=-1|Color=8388608|FontID=1|IsHidden=T|Text=*|Name=DocumentName|ReadOnlyState=1
|RECORD=41|IndexInSheet=119|OwnerPartId=-1|Color=8388608|FontID=1|IsHidden=T|Text=*|Name=ModifiedDate|ReadOnlyState=1
|RECORD=41|IndexInSheet=120|OwnerPartId=-1|Color=8388608|FontID=1|IsHidden=T|Text=*|Name=ApprovedBy|ReadOnlyState=1
|RECORD=41|IndexInSheet=121|OwnerPartId=-1|Color=8388608|FontID=1|IsHidden=T|Text=*|Name=CheckedBy|ReadOnlyState=1
|RECORD=41|IndexInSheet=122|OwnerPartId=-1|Color=8388608|FontID=1|IsHidden=T|Text=*|Name=Author|ReadOnlyState=1
|RECORD=41|IndexInSheet=123|OwnerPartId=-1|Color=8388608|FontID=1|IsHidden=T|Text=*|Name=CompanyName|ReadOnlyState=1
|RECORD=41|IndexInSheet=124|OwnerPartId=-1|Color=8388608|FontID=1|IsHidden=T|Text=*|Name=DrawnBy|ReadOnlyState=1
|RECORD=41|IndexInSheet=125|OwnerPartId=-1|Color=8388608|FontID=1|IsHidden=T|Text=*|Name=Engineer|ReadOnlyState=1
|RECORD=41|IndexInSheet=126|OwnerPartId=-1|Color=8388608|FontID=1|IsHidden=T|Text=*|Name=Organization|ReadOnlyState=1
|RECORD=41|IndexInSheet=127|OwnerPartId=-1|Color=8388608|FontID=1|IsHidden=T|Text=*|Name=Address1|ReadOnlyState=1
|RECORD=41|IndexInSheet=128|OwnerPartId=-1|Color=8388608|FontID=1|IsHidden=T|Text=*|Name=Address2|ReadOnlyState=1
|RECORD=41|IndexInSheet=129|OwnerPartId=-1|Color=8388608|FontID=1|IsHidden=T|Text=*|Name=Address3|ReadOnlyState=1
|RECORD=41|IndexInSheet=130|OwnerPartId=-1|Color=8388608|FontID=1|IsHidden=T|Text=*|Name=Address4|ReadOnlyState=1
|RECORD=41|IndexInSheet=131|OwnerPartId=-1|Color=8388608|FontID=1|IsHidden=T|Text=Time Card|Name=Title|ReadOnlyState=1
|RECORD=41|IndexInSheet=132|OwnerPartId=-1|Color=8388608|FontID=1|IsHidden=T|Text=*|Name=DocumentNumber|ReadOnlyState=1
|RECORD=41|IndexInSheet=133|OwnerPartId=-1|Color=8388608|FontID=1|IsHidden=T|Text=*|Name=Revision|ReadOnlyState=1
|RECORD=41|IndexInSheet=134|OwnerPartId=-1|Color=8388608|FontID=1|IsHidden=T|Text=2|Name=SheetNumber|ReadOnlyState=1
|RECORD=41|IndexInSheet=135|OwnerPartId=-1|Color=8388608|FontID=1|IsHidden=T|Text=8|Name=SheetTotal|ReadOnlyState=1
|RECORD=41|IndexInSheet=136|OwnerPartId=-1|Color=8388608|FontID=1|IsHidden=T|Text=*|Name=Rule|ReadOnlyState=1
|RECORD=41|IndexInSheet=137|OwnerPartId=-1|Color=8388608|FontID=1|IsHidden=T|Text=*|Name=ImagePath|ReadOnlyState=1
|RECORD=41|IndexInSheet=138|OwnerPartId=-1|Color=8388608|FontID=1|IsHidden=T|Text=*|Name=ProjectName|ReadOnlyState=1
|RECORD=41|IndexInSheet=139|OwnerPartId=-1|Color=8388608|FontID=1|IsHidden=T|Text=*|Name=Application_BuildNumber|ReadOnlyState=1
|RECORD=41|IndexInSheet=140|OwnerPartId=-1|Color=8388608|FontID=1|IsHidden=T|Name=SheetSymbolDesignator|ReadOnlyState=1
|RECORD=41|IndexInSheet=141|OwnerPartId=-1|Color=8388608|FontID=1|IsHidden=T|Name=VersionControl_RevNumberShort|ReadOnlyState=1
|RECORD=41|IndexInSheet=142|OwnerPartId=-1|Color=8388608|FontID=1|IsHidden=T|Name=VersionControl_ProjFolderRevNumberShort|ReadOnlyState=1
|RECORD=41|IndexInSheet=143|OwnerPartId=-1|Location.X=839|Location.Y=9|Color=8388608|FontID=1|IsHidden=T|Text=*|Name=Title2
|RECORD=41|IndexInSheet=144|OwnerPartId=-1|Location.Y=-10|Color=8388608|FontID=1|IsHidden=T|Text=*|Name=Project
|RECORD=41|IndexInSheet=145|OwnerPartId=-1|Location.Y=-10|Color=8388608|FontID=1|IsHidden=T|Text=--/--/--|Name=ENG_APP_DATE
|RECORD=41|IndexInSheet=146|OwnerPartId=-1|Location.Y=-10|Color=8388608|FontID=1|IsHidden=T|Text=--/--/--|Name=DSN_APP_DATE
|RECORD=41|IndexInSheet=147|OwnerPartId=-1|Location.Y=-10|Color=8388608|FontID=1|IsHidden=T|Text=--/--/--|Name=CHK_APP_DATE
|RECORD=27|IndexInSheet=148|OwnerPartId=-1|LineWidth=1|Color=8388608|LocationCount=5|X1=644|Y1=295|X2=534|Y2=295|X3=464|Y3=295|X4=444|Y4=295|X5=444|Y5=205
|RECORD=27|IndexInSheet=149|OwnerPartId=-1|LineWidth=1|Color=8388608|LocationCount=8|X1=1244|Y1=555|X2=1244|Y2=505|X3=1244|Y3=445|X4=1244|Y4=385|X5=1244|Y5=325|X6=1244|Y6=255|X7=1244|Y7=185|X8=1214|Y8=185
|RECORD=27|IndexInSheet=150|OwnerPartId=-1|LineWidth=1|Color=8388608|LocationCount=3|X1=494|Y1=250|X2=494|Y2=415|X3=494|Y3=440
|RECORD=29|IndexInSheet=-1|OwnerPartId=-1|Location.X=364|Location.Y=385|Color=128
|RECORD=29|IndexInSheet=-1|OwnerPartId=-1|Location.X=464|Location.Y=295|Color=128
|RECORD=29|IndexInSheet=-1|OwnerPartId=-1|Location.X=494|Location.Y=415|Color=128
|RECORD=29|IndexInSheet=-1|OwnerPartId=-1|Location.X=534|Location.Y=295|Color=128
|RECORD=29|IndexInSheet=-1|OwnerPartId=-1|Location.X=614|Location.Y=225|Color=128
|RECORD=29|IndexInSheet=-1|OwnerPartId=-1|Location.X=614|Location.Y=235|Color=128
|RECORD=29|IndexInSheet=-1|OwnerPartId=-1|Location.X=614|Location.Y=245|Color=128
|RECORD=29|IndexInSheet=-1|OwnerPartId=-1|Location.X=614|Location.Y=255|Color=128
|RECORD=29|IndexInSheet=-1|OwnerPartId=-1|Location.X=1244|Location.Y=255|Color=128
|RECORD=29|IndexInSheet=-1|OwnerPartId=-1|Location.X=1244|Location.Y=325|Color=128
|RECORD=29|IndexInSheet=-1|OwnerPartId=-1|Location.X=1244|Location.Y=385|Color=128
|RECORD=29|IndexInSheet=-1|OwnerPartId=-1|Location.X=1244|Location.Y=445|Color=128
|RECORD=29|IndexInSheet=-1|OwnerPartId=-1|Location.X=1244|Location.Y=505|Color=128